FILE_TYPE = MACRO_DRAWING;
SET COLOR_WIRE YELLOW;
SET COLOR_PROP MONO;
SET COLOR_DOT WHITE;
SET COLOR_ARC YELLOW;
SET COLOR_BODY GREEN;
SET COLOR_NOTE MONO;
SET PROP_DISPLAY VALUE;
SET PAGE_NUMBER P189;
FORCEADD OFFPAGE..1
(-2650 2875);
FORCEPROP 2 LAST $XR0 120 
J 0
(-2902 2875);
DISPLAY 0.638298 (-2902 2875);
PAINT MONO (-2902 2875);
FORCEPROP 2 LAST PATH I1
J 0
(-2925 2925);
DISPLAY 1.021277 (-2925 2925);
PAINT ORANGE (-2925 2925);
DISPLAY INVISIBLE (-2925 2925);
FORCEPROP 2 LAST CDS_LIB mstr_standard
J 0
(-2650 2875);
PAINT ORANGE (-2650 2875);
DISPLAY INVISIBLE (-2650 2875);
FORCEPROP 1 LAST COMMENT_BODY TRUE
J 0
(-2525 2775);
DISPLAY 0.872340 (-2525 2775);
PAINT GREEN (-2525 2775);
DISPLAY INVISIBLE (-2525 2775);
FORCEPROP 1 LAST OFFPAGE TRUE
J 0
(-2325 2750);
DISPLAY 0.872340 (-2325 2750);
PAINT GREEN (-2325 2750);
DISPLAY INVISIBLE (-2325 2750);
FORCEADD OFFPAGE..1
(-2650 4675);
FORCEPROP 2 LAST $XR0 151 
J 0
(-2902 4675);
DISPLAY 0.638298 (-2902 4675);
PAINT MONO (-2902 4675);
FORCEPROP 2 LAST $XR1 144 
J 0
(-2902 4675);
DISPLAY 0.638298 (-2902 4675);
PAINT MONO (-2902 4675);
FORCEPROP 2 LAST PATH I10
J 0
(-2925 4725);
DISPLAY 1.021277 (-2925 4725);
PAINT ORANGE (-2925 4725);
DISPLAY INVISIBLE (-2925 4725);
FORCEPROP 2 LAST CDS_LIB mstr_standard
J 0
(-2650 4675);
PAINT ORANGE (-2650 4675);
DISPLAY INVISIBLE (-2650 4675);
FORCEPROP 1 LAST COMMENT_BODY TRUE
J 0
(-2525 4575);
DISPLAY 0.872340 (-2525 4575);
PAINT GREEN (-2525 4575);
DISPLAY INVISIBLE (-2525 4575);
FORCEPROP 1 LAST OFFPAGE TRUE
J 0
(-2325 4550);
DISPLAY 0.872340 (-2325 4550);
PAINT GREEN (-2325 4550);
DISPLAY INVISIBLE (-2325 4550);
FORCEADD OFFPAGE..1
(-2650 4500);
FORCEPROP 2 LAST $XR0 120 
J 0
(-2902 4500);
DISPLAY 0.638298 (-2902 4500);
PAINT MONO (-2902 4500);
FORCEPROP 2 LAST PATH I11
J 0
(-2925 4550);
DISPLAY 1.021277 (-2925 4550);
PAINT ORANGE (-2925 4550);
DISPLAY INVISIBLE (-2925 4550);
FORCEPROP 2 LAST CDS_LIB mstr_standard
J 0
(-2650 4500);
PAINT ORANGE (-2650 4500);
DISPLAY INVISIBLE (-2650 4500);
FORCEPROP 1 LAST COMMENT_BODY TRUE
J 0
(-2525 4400);
DISPLAY 0.872340 (-2525 4400);
PAINT GREEN (-2525 4400);
DISPLAY INVISIBLE (-2525 4400);
FORCEPROP 1 LAST OFFPAGE TRUE
J 0
(-2325 4375);
DISPLAY 0.872340 (-2325 4375);
PAINT GREEN (-2325 4375);
DISPLAY INVISIBLE (-2325 4375);
FORCEADD OFFPAGE..1
(-2650 4300);
FORCEPROP 2 LAST $XR0 120 
J 0
(-2902 4300);
DISPLAY 0.638298 (-2902 4300);
PAINT MONO (-2902 4300);
FORCEPROP 2 LAST PATH I12
J 0
(-2900 4350);
DISPLAY 1.021277 (-2900 4350);
PAINT ORANGE (-2900 4350);
DISPLAY INVISIBLE (-2900 4350);
FORCEPROP 2 LAST CDS_LIB mstr_standard
J 0
(-2650 4300);
PAINT ORANGE (-2650 4300);
DISPLAY INVISIBLE (-2650 4300);
FORCEPROP 1 LAST COMMENT_BODY TRUE
J 0
(-2525 4200);
DISPLAY 0.872340 (-2525 4200);
PAINT GREEN (-2525 4200);
DISPLAY INVISIBLE (-2525 4200);
FORCEPROP 1 LAST OFFPAGE TRUE
J 0
(-2325 4175);
DISPLAY 0.872340 (-2325 4175);
PAINT GREEN (-2325 4175);
DISPLAY INVISIBLE (-2325 4175);
FORCEADD RES..1
(-1900 4125);
FORCEPROP 1 LAST WATTAGE 1/16W
J 2
(-1975 4075);
DISPLAY 0.617021 (-1975 4075);
PAINT SKYBLUE (-1975 4075);
FORCEPROP 1 LAST PACK_TYPE 0402
J 0
(-1800 4075);
DISPLAY 0.617021 (-1800 4075);
PAINT SKYBLUE (-1800 4075);
FORCEPROP 1 LAST MATERIAL EMPTY
J 0
(-1950 4075);
DISPLAY 0.617021 (-1950 4075);
PAINT RED (-1950 4075);
FORCEPROP 1 LAST VALUE 0.0
J 2
(-2075 4125);
DISPLAY 0.617021 (-2075 4125);
PAINT SKYBLUE (-2075 4125);
FORCEPROP 1 LAST TOLERANCE 5%
J 0
(-2050 4125);
DISPLAY 0.617021 (-2050 4125);
PAINT SKYBLUE (-2050 4125);
FORCEPROP 1 LASTPIN (-2000 4125) $PN 1
J 0
(-1988 4137);
DISPLAY 0.617021 (-1988 4137);
PAINT ORANGE (-1988 4137);
FORCEPROP 1 LAST LOCATION R7G18
J 0
(-1950 4175);
DISPLAY 0.617021 (-1950 4175);
PAINT AQUA (-1950 4175);
FORCEPROP 1 LASTPIN (-1800 4125) $PN 2
J 0
(-1838 4137);
DISPLAY 0.617021 (-1838 4137);
PAINT ORANGE (-1838 4137);
FORCEPROP 1 LAST PART_NUMBER G21497-005
J 0
(-1750 4125);
DISPLAY 0.617021 (-1750 4125);
PAINT BLUE (-1750 4125);
FORCEPROP 2 LAST CDS_LOCATION R7G18
J 0
(-1950 4175);
DISPLAY 0.617021 (-1950 4175);
PAINT AQUA (-1950 4175);
DISPLAY INVISIBLE (-1950 4175);
FORCEPROP 2 LAST ROOM BMC_DEBUG_HEADER
J 0
(-1950 4225);
DISPLAY 1.021277 (-1950 4225);
PAINT ORANGE (-1950 4225);
DISPLAY INVISIBLE (-1950 4225);
FORCEPROP 1 LAST PATH I13
J 0
(-1950 4275);
DISPLAY 0.978723 (-1950 4275);
PAINT WHITE (-1950 4275);
DISPLAY INVISIBLE (-1950 4275);
FORCEPROP 2 LAST BOM_COST DEBUG
J 0
(-1950 4275);
DISPLAY 1.021277 (-1950 4275);
PAINT ORANGE (-1950 4275);
DISPLAY INVISIBLE (-1950 4275);
FORCEPROP 2 LAST CDS_LIB mstr_discrete
J 0
(-1900 4125);
PAINT MONO (-1900 4125);
DISPLAY INVISIBLE (-1900 4125);
FORCEPROP 2 LAST SEC 1
J 0
(-1950 4325);
PAINT MONO (-1950 4325);
DISPLAY INVISIBLE (-1950 4325);
FORCEPROP 2 LAST SEC_TYPE 0402
J 0
(-1950 4325);
DISPLAY 1.021277 (-1950 4325);
PAINT ORANGE (-1950 4325);
DISPLAY INVISIBLE (-1950 4325);
FORCEADD OFFPAGE..2
(-1175 3575);
FORCEPROP 2 LAST $XR0 189 
J 0
(-986 3575);
DISPLAY 0.638298 (-986 3575);
PAINT MONO (-986 3575);
FORCEPROP 1 LAST COMMENT_BODY TRUE
J 0
(-1220 3480);
DISPLAY 0.872340 (-1220 3480);
PAINT GREEN (-1220 3480);
DISPLAY INVISIBLE (-1220 3480);
FORCEPROP 2 LAST CDS_LIB mstr_standard
J 0
(-1175 3575);
PAINT ORANGE (-1175 3575);
DISPLAY INVISIBLE (-1175 3575);
FORCEPROP 2 LAST PATH I14
J 0
(-975 3625);
DISPLAY 1.021277 (-975 3625);
PAINT ORANGE (-975 3625);
DISPLAY INVISIBLE (-975 3625);
FORCEPROP 1 LAST OFFPAGE TRUE
J 0
(-850 3450);
DISPLAY 0.872340 (-850 3450);
PAINT GREEN (-850 3450);
DISPLAY INVISIBLE (-850 3450);
FORCEADD OFFPAGE..2
(-1175 2875);
FORCEPROP 2 LAST $XR0 189 
J 0
(-986 2875);
DISPLAY 0.638298 (-986 2875);
PAINT MONO (-986 2875);
FORCEPROP 1 LAST COMMENT_BODY TRUE
J 0
(-1220 2780);
DISPLAY 0.872340 (-1220 2780);
PAINT GREEN (-1220 2780);
DISPLAY INVISIBLE (-1220 2780);
FORCEPROP 2 LAST CDS_LIB mstr_standard
J 0
(-1175 2875);
PAINT ORANGE (-1175 2875);
DISPLAY INVISIBLE (-1175 2875);
FORCEPROP 2 LAST PATH I15
J 0
(-975 2925);
DISPLAY 1.021277 (-975 2925);
PAINT ORANGE (-975 2925);
DISPLAY INVISIBLE (-975 2925);
FORCEPROP 1 LAST OFFPAGE TRUE
J 0
(-850 2750);
DISPLAY 0.872340 (-850 2750);
PAINT GREEN (-850 2750);
DISPLAY INVISIBLE (-850 2750);
FORCEADD OFFPAGE..4
(-1175 2150);
FORCEPROP 2 LAST $XR0 189 
J 0
(-989 2150);
DISPLAY 0.638298 (-989 2150);
PAINT MONO (-989 2150);
FORCEPROP 1 LAST OFFPAGE TRUE
J 0
(-850 2025);
DISPLAY 0.872340 (-850 2025);
PAINT GREEN (-850 2025);
DISPLAY INVISIBLE (-850 2025);
FORCEPROP 1 LAST COMMENT_BODY TRUE
J 0
(-1200 2050);
DISPLAY 0.872340 (-1200 2050);
PAINT GREEN (-1200 2050);
DISPLAY INVISIBLE (-1200 2050);
FORCEPROP 2 LAST CDS_LIB mstr_standard
J 0
(-1175 2150);
PAINT ORANGE (-1175 2150);
DISPLAY INVISIBLE (-1175 2150);
FORCEPROP 2 LAST PATH I16
J 0
(-975 2200);
DISPLAY 1.021277 (-975 2200);
PAINT ORANGE (-975 2200);
DISPLAY INVISIBLE (-975 2200);
FORCEADD RES..1
(-1900 3950);
FORCEPROP 1 LAST VALUE 0.0
J 2
(-2075 3950);
DISPLAY 0.617021 (-2075 3950);
PAINT SKYBLUE (-2075 3950);
FORCEPROP 1 LAST WATTAGE 1/16W
J 2
(-1975 3900);
DISPLAY 0.617021 (-1975 3900);
PAINT SKYBLUE (-1975 3900);
FORCEPROP 1 LAST TOLERANCE 5%
J 0
(-2050 3950);
DISPLAY 0.617021 (-2050 3950);
PAINT SKYBLUE (-2050 3950);
FORCEPROP 1 LASTPIN (-2000 3950) $PN 1
J 0
(-1988 3962);
DISPLAY 0.617021 (-1988 3962);
PAINT ORANGE (-1988 3962);
FORCEPROP 1 LAST MATERIAL CHIP
J 0
(-1950 3900);
DISPLAY 0.617021 (-1950 3900);
PAINT SKYBLUE (-1950 3900);
FORCEPROP 1 LAST LOCATION R8G8
J 0
(-1950 4000);
DISPLAY 0.617021 (-1950 4000);
PAINT AQUA (-1950 4000);
FORCEPROP 1 LASTPIN (-1800 3950) $PN 2
J 0
(-1838 3962);
DISPLAY 0.617021 (-1838 3962);
PAINT ORANGE (-1838 3962);
FORCEPROP 1 LAST PACK_TYPE 0402
J 0
(-1800 3900);
DISPLAY 0.617021 (-1800 3900);
PAINT SKYBLUE (-1800 3900);
FORCEPROP 1 LAST PART_NUMBER G21497-005
J 0
(-1750 3950);
DISPLAY 0.617021 (-1750 3950);
PAINT BLUE (-1750 3950);
FORCEPROP 2 LAST ROOM BMC_DEBUG_HEADER
J 0
(-1950 4050);
DISPLAY 1.021277 (-1950 4050);
PAINT ORANGE (-1950 4050);
DISPLAY INVISIBLE (-1950 4050);
FORCEPROP 2 LAST CDS_LOCATION R8G8
J 0
(-1950 4000);
DISPLAY 0.617021 (-1950 4000);
PAINT AQUA (-1950 4000);
DISPLAY INVISIBLE (-1950 4000);
FORCEPROP 2 LAST CDS_LIB mstr_discrete
J 0
(-1900 3950);
PAINT ORANGE (-1900 3950);
DISPLAY INVISIBLE (-1900 3950);
FORCEPROP 1 LAST PATH I17
J 0
(-1950 4100);
DISPLAY 0.978723 (-1950 4100);
PAINT WHITE (-1950 4100);
DISPLAY INVISIBLE (-1950 4100);
FORCEPROP 2 LAST SEC 1
J 0
(-1950 4150);
DISPLAY 0.680851 (-1950 4150);
PAINT MONO (-1950 4150);
DISPLAY INVISIBLE (-1950 4150);
FORCEPROP 2 LAST BOM_COST DEBUG
J 0
(-1950 4100);
DISPLAY 1.021277 (-1950 4100);
PAINT ORANGE (-1950 4100);
DISPLAY INVISIBLE (-1950 4100);
FORCEPROP 2 LAST SEC_TYPE 0402
J 0
(-1950 4150);
DISPLAY 1.021277 (-1950 4150);
PAINT ORANGE (-1950 4150);
DISPLAY INVISIBLE (-1950 4150);
FORCEADD RES..1
(-1900 3775);
FORCEPROP 1 LAST VALUE 0.0
J 2
(-2075 3775);
DISPLAY 0.617021 (-2075 3775);
PAINT SKYBLUE (-2075 3775);
FORCEPROP 1 LAST WATTAGE 1/16W
J 2
(-1950 3725);
DISPLAY 0.617021 (-1950 3725);
PAINT SKYBLUE (-1950 3725);
FORCEPROP 1 LAST TOLERANCE 5%
J 0
(-2050 3775);
DISPLAY 0.617021 (-2050 3775);
PAINT SKYBLUE (-2050 3775);
FORCEPROP 1 LASTPIN (-2000 3775) $PN 1
J 0
(-1988 3787);
DISPLAY 0.617021 (-1988 3787);
PAINT ORANGE (-1988 3787);
FORCEPROP 1 LAST MATERIAL CHIP
J 0
(-1925 3725);
DISPLAY 0.617021 (-1925 3725);
PAINT SKYBLUE (-1925 3725);
FORCEPROP 1 LASTPIN (-1800 3775) $PN 2
J 0
(-1838 3787);
DISPLAY 0.617021 (-1838 3787);
PAINT ORANGE (-1838 3787);
FORCEPROP 1 LAST LOCATION R8G7
J 0
(-1950 3825);
DISPLAY 0.617021 (-1950 3825);
PAINT AQUA (-1950 3825);
FORCEPROP 1 LAST PACK_TYPE 0402
J 0
(-1825 3725);
DISPLAY 0.617021 (-1825 3725);
PAINT SKYBLUE (-1825 3725);
FORCEPROP 1 LAST PART_NUMBER G21497-005
J 0
(-1750 3775);
DISPLAY 0.617021 (-1750 3775);
PAINT BLUE (-1750 3775);
FORCEPROP 2 LAST CDS_LIB mstr_discrete
J 0
(-1900 3775);
PAINT ORANGE (-1900 3775);
DISPLAY INVISIBLE (-1900 3775);
FORCEPROP 2 LAST CDS_LOCATION R8G7
J 0
(-1950 3825);
DISPLAY 0.617021 (-1950 3825);
PAINT AQUA (-1950 3825);
DISPLAY INVISIBLE (-1950 3825);
FORCEPROP 2 LAST BOM_COST DEBUG
J 0
(-1950 3925);
DISPLAY 1.021277 (-1950 3925);
PAINT ORANGE (-1950 3925);
DISPLAY INVISIBLE (-1950 3925);
FORCEPROP 1 LAST PATH I18
J 0
(-1950 3925);
DISPLAY 0.978723 (-1950 3925);
PAINT WHITE (-1950 3925);
DISPLAY INVISIBLE (-1950 3925);
FORCEPROP 2 LAST ROOM BMC_DEBUG_HEADER
J 0
(-1950 3875);
DISPLAY 1.021277 (-1950 3875);
PAINT ORANGE (-1950 3875);
DISPLAY INVISIBLE (-1950 3875);
FORCEPROP 2 LAST SEC_TYPE 0402
J 0
(-1950 3975);
DISPLAY 1.021277 (-1950 3975);
PAINT ORANGE (-1950 3975);
DISPLAY INVISIBLE (-1950 3975);
FORCEPROP 2 LAST SEC 1
J 0
(-1950 3975);
DISPLAY 0.680851 (-1950 3975);
PAINT MONO (-1950 3975);
DISPLAY INVISIBLE (-1950 3975);
FORCEADD RES..1
(-1900 3400);
FORCEPROP 1 LAST VALUE 0.0
J 2
(-2075 3400);
DISPLAY 0.617021 (-2075 3400);
PAINT SKYBLUE (-2075 3400);
FORCEPROP 1 LAST WATTAGE 1/16W
J 2
(-1975 3350);
DISPLAY 0.617021 (-1975 3350);
PAINT SKYBLUE (-1975 3350);
FORCEPROP 1 LAST TOLERANCE 5%
J 0
(-2050 3400);
DISPLAY 0.617021 (-2050 3400);
PAINT SKYBLUE (-2050 3400);
FORCEPROP 1 LASTPIN (-2000 3400) $PN 1
J 0
(-1988 3412);
DISPLAY 0.617021 (-1988 3412);
PAINT ORANGE (-1988 3412);
FORCEPROP 1 LAST LOCATION R8G11
J 0
(-1950 3450);
DISPLAY 0.617021 (-1950 3450);
PAINT AQUA (-1950 3450);
FORCEPROP 1 LAST MATERIAL EMPTY
J 0
(-1950 3350);
DISPLAY 0.617021 (-1950 3350);
PAINT RED (-1950 3350);
FORCEPROP 1 LASTPIN (-1800 3400) $PN 2
J 0
(-1838 3412);
DISPLAY 0.617021 (-1838 3412);
PAINT ORANGE (-1838 3412);
FORCEPROP 1 LAST PACK_TYPE 0402
J 0
(-1800 3350);
DISPLAY 0.617021 (-1800 3350);
PAINT SKYBLUE (-1800 3350);
FORCEPROP 1 LAST PART_NUMBER G21497-005
J 0
(-1750 3400);
DISPLAY 0.617021 (-1750 3400);
PAINT BLUE (-1750 3400);
FORCEPROP 2 LAST CDS_LOCATION R8G11
J 0
(-1950 3450);
DISPLAY 0.617021 (-1950 3450);
PAINT AQUA (-1950 3450);
DISPLAY INVISIBLE (-1950 3450);
FORCEPROP 2 LAST ROOM BMC_DEBUG_HEADER
J 0
(-1950 3500);
DISPLAY 1.021277 (-1950 3500);
PAINT ORANGE (-1950 3500);
DISPLAY INVISIBLE (-1950 3500);
FORCEPROP 2 LAST CDS_LIB mstr_discrete
J 0
(-1900 3400);
PAINT MONO (-1900 3400);
DISPLAY INVISIBLE (-1900 3400);
FORCEPROP 1 LAST PATH I19
J 0
(-1950 3550);
DISPLAY 0.978723 (-1950 3550);
PAINT WHITE (-1950 3550);
DISPLAY INVISIBLE (-1950 3550);
FORCEPROP 2 LAST BOM_COST DEBUG
J 0
(-1950 3550);
DISPLAY 1.021277 (-1950 3550);
PAINT ORANGE (-1950 3550);
DISPLAY INVISIBLE (-1950 3550);
FORCEPROP 2 LAST SEC 1
J 0
(-1950 3600);
PAINT MONO (-1950 3600);
DISPLAY INVISIBLE (-1950 3600);
FORCEPROP 2 LAST SEC_TYPE 0402
J 0
(-1950 3600);
DISPLAY 1.021277 (-1950 3600);
PAINT ORANGE (-1950 3600);
DISPLAY INVISIBLE (-1950 3600);
FORCEADD OFFPAGE..1
(-2650 3075);
FORCEPROP 2 LAST $XR0 191 
J 0
(-2902 3075);
DISPLAY 0.638298 (-2902 3075);
PAINT MONO (-2902 3075);
FORCEPROP 1 LAST COMMENT_BODY TRUE
J 0
(-2525 2975);
DISPLAY 0.872340 (-2525 2975);
PAINT GREEN (-2525 2975);
DISPLAY INVISIBLE (-2525 2975);
FORCEPROP 1 LAST OFFPAGE TRUE
J 0
(-2325 2950);
DISPLAY 0.872340 (-2325 2950);
PAINT GREEN (-2325 2950);
DISPLAY INVISIBLE (-2325 2950);
FORCEPROP 2 LAST PATH I2
J 0
(-2925 3125);
DISPLAY 1.021277 (-2925 3125);
PAINT ORANGE (-2925 3125);
DISPLAY INVISIBLE (-2925 3125);
FORCEPROP 2 LAST CDS_LIB mstr_standard
J 0
(-2650 3075);
PAINT ORANGE (-2650 3075);
DISPLAY INVISIBLE (-2650 3075);
FORCEADD RES..1
(-1900 3250);
FORCEPROP 1 LAST VALUE 0.0
J 2
(-2075 3250);
DISPLAY 0.617021 (-2075 3250);
PAINT SKYBLUE (-2075 3250);
FORCEPROP 1 LAST WATTAGE 1/16W
J 2
(-1975 3200);
DISPLAY 0.617021 (-1975 3200);
PAINT SKYBLUE (-1975 3200);
FORCEPROP 1 LAST TOLERANCE 5%
J 0
(-2050 3250);
DISPLAY 0.617021 (-2050 3250);
PAINT SKYBLUE (-2050 3250);
FORCEPROP 1 LASTPIN (-2000 3250) $PN 1
J 0
(-1988 3262);
DISPLAY 0.617021 (-1988 3262);
PAINT ORANGE (-1988 3262);
FORCEPROP 1 LAST MATERIAL CHIP
J 0
(-1925 3200);
DISPLAY 0.617021 (-1925 3200);
PAINT SKYBLUE (-1925 3200);
FORCEPROP 1 LAST LOCATION R8G14
J 0
(-1950 3300);
DISPLAY 0.617021 (-1950 3300);
PAINT AQUA (-1950 3300);
FORCEPROP 1 LASTPIN (-1800 3250) $PN 2
J 0
(-1838 3262);
DISPLAY 0.617021 (-1838 3262);
PAINT ORANGE (-1838 3262);
FORCEPROP 1 LAST PACK_TYPE 0402
J 0
(-1800 3200);
DISPLAY 0.617021 (-1800 3200);
PAINT SKYBLUE (-1800 3200);
FORCEPROP 1 LAST PART_NUMBER G21497-005
J 0
(-1750 3250);
DISPLAY 0.617021 (-1750 3250);
PAINT BLUE (-1750 3250);
FORCEPROP 2 LAST CDS_LOCATION R8G14
J 0
(-1950 3300);
DISPLAY 0.617021 (-1950 3300);
PAINT AQUA (-1950 3300);
DISPLAY INVISIBLE (-1950 3300);
FORCEPROP 2 LAST CDS_LIB mstr_discrete
J 0
(-1900 3250);
PAINT ORANGE (-1900 3250);
DISPLAY INVISIBLE (-1900 3250);
FORCEPROP 2 LAST BOM_COST DEBUG
J 0
(-1950 3400);
DISPLAY 1.021277 (-1950 3400);
PAINT ORANGE (-1950 3400);
DISPLAY INVISIBLE (-1950 3400);
FORCEPROP 1 LAST PATH I20
J 0
(-1950 3400);
DISPLAY 0.978723 (-1950 3400);
PAINT WHITE (-1950 3400);
DISPLAY INVISIBLE (-1950 3400);
FORCEPROP 2 LAST ROOM BMC_DEBUG_HEADER
J 0
(-1950 3350);
DISPLAY 1.021277 (-1950 3350);
PAINT ORANGE (-1950 3350);
DISPLAY INVISIBLE (-1950 3350);
FORCEPROP 2 LAST SEC 1
J 0
(-1950 3450);
DISPLAY 0.680851 (-1950 3450);
PAINT MONO (-1950 3450);
DISPLAY INVISIBLE (-1950 3450);
FORCEPROP 2 LAST SEC_TYPE 0402
J 0
(-1950 3450);
DISPLAY 1.021277 (-1950 3450);
PAINT ORANGE (-1950 3450);
DISPLAY INVISIBLE (-1950 3450);
FORCEADD RES..1
(-1900 3575);
FORCEPROP 1 LAST VALUE 0.0
J 2
(-2075 3575);
DISPLAY 0.617021 (-2075 3575);
PAINT SKYBLUE (-2075 3575);
FORCEPROP 1 LAST WATTAGE 1/16W
J 2
(-1975 3525);
DISPLAY 0.617021 (-1975 3525);
PAINT SKYBLUE (-1975 3525);
FORCEPROP 1 LAST TOLERANCE 5%
J 0
(-2050 3575);
DISPLAY 0.617021 (-2050 3575);
PAINT SKYBLUE (-2050 3575);
FORCEPROP 1 LAST MATERIAL EMPTY
J 0
(-1950 3525);
DISPLAY 0.617021 (-1950 3525);
PAINT RED (-1950 3525);
FORCEPROP 1 LAST PACK_TYPE 0402
J 0
(-1800 3525);
DISPLAY 0.617021 (-1800 3525);
PAINT SKYBLUE (-1800 3525);
FORCEPROP 1 LASTPIN (-2000 3575) $PN 1
J 0
(-1988 3587);
DISPLAY 0.617021 (-1988 3587);
PAINT ORANGE (-1988 3587);
FORCEPROP 1 LAST LOCATION R8G12
J 0
(-1950 3625);
DISPLAY 0.617021 (-1950 3625);
PAINT AQUA (-1950 3625);
FORCEPROP 1 LASTPIN (-1800 3575) $PN 2
J 0
(-1838 3587);
DISPLAY 0.617021 (-1838 3587);
PAINT ORANGE (-1838 3587);
FORCEPROP 1 LAST PART_NUMBER G21497-005
J 0
(-1750 3575);
DISPLAY 0.617021 (-1750 3575);
PAINT BLUE (-1750 3575);
FORCEPROP 2 LAST CDS_LIB mstr_discrete
J 0
(-1900 3575);
PAINT ORANGE (-1900 3575);
DISPLAY INVISIBLE (-1900 3575);
FORCEPROP 2 LAST CDS_LOCATION R8G12
J 0
(-1950 3625);
DISPLAY 0.617021 (-1950 3625);
PAINT AQUA (-1950 3625);
DISPLAY INVISIBLE (-1950 3625);
FORCEPROP 2 LAST ROOM BMC_DEBUG_HEADER
J 0
(-1950 3675);
DISPLAY 1.021277 (-1950 3675);
PAINT ORANGE (-1950 3675);
DISPLAY INVISIBLE (-1950 3675);
FORCEPROP 2 LAST BOM_COST DEBUG
J 0
(-1950 3725);
DISPLAY 1.021277 (-1950 3725);
PAINT ORANGE (-1950 3725);
DISPLAY INVISIBLE (-1950 3725);
FORCEPROP 2 LAST SEC 1
J 0
(-1950 3775);
DISPLAY 0.680851 (-1950 3775);
PAINT MONO (-1950 3775);
DISPLAY INVISIBLE (-1950 3775);
FORCEPROP 2 LAST SEC_TYPE 0402
J 0
(-1950 3775);
DISPLAY 1.021277 (-1950 3775);
PAINT ORANGE (-1950 3775);
DISPLAY INVISIBLE (-1950 3775);
FORCEPROP 1 LAST PATH I21
J 0
(-1950 3725);
DISPLAY 0.978723 (-1950 3725);
PAINT WHITE (-1950 3725);
DISPLAY INVISIBLE (-1950 3725);
FORCEADD RES..1
(-1900 2700);
FORCEPROP 1 LAST VALUE 0.0
J 2
(-2075 2700);
DISPLAY 0.617021 (-2075 2700);
PAINT SKYBLUE (-2075 2700);
FORCEPROP 1 LAST WATTAGE 1/16W
J 2
(-1975 2650);
DISPLAY 0.617021 (-1975 2650);
PAINT SKYBLUE (-1975 2650);
FORCEPROP 1 LAST TOLERANCE 5%
J 0
(-2050 2700);
DISPLAY 0.617021 (-2050 2700);
PAINT SKYBLUE (-2050 2700);
FORCEPROP 1 LASTPIN (-2000 2700) $PN 1
J 0
(-1988 2712);
DISPLAY 0.617021 (-1988 2712);
PAINT ORANGE (-1988 2712);
FORCEPROP 1 LAST LOCATION R8G16
J 0
(-1950 2750);
DISPLAY 0.617021 (-1950 2750);
PAINT AQUA (-1950 2750);
FORCEPROP 1 LAST MATERIAL EMPTY
J 0
(-1950 2650);
DISPLAY 0.617021 (-1950 2650);
PAINT RED (-1950 2650);
FORCEPROP 1 LASTPIN (-1800 2700) $PN 2
J 0
(-1838 2712);
DISPLAY 0.617021 (-1838 2712);
PAINT ORANGE (-1838 2712);
FORCEPROP 1 LAST PACK_TYPE 0402
J 0
(-1800 2650);
DISPLAY 0.617021 (-1800 2650);
PAINT SKYBLUE (-1800 2650);
FORCEPROP 1 LAST PART_NUMBER G21497-005
J 0
(-1750 2700);
DISPLAY 0.617021 (-1750 2700);
PAINT BLUE (-1750 2700);
FORCEPROP 2 LAST CDS_LOCATION R8G16
J 0
(-1950 2750);
DISPLAY 0.617021 (-1950 2750);
PAINT AQUA (-1950 2750);
DISPLAY INVISIBLE (-1950 2750);
FORCEPROP 2 LAST CDS_LIB mstr_discrete
J 0
(-1900 2700);
PAINT MONO (-1900 2700);
DISPLAY INVISIBLE (-1900 2700);
FORCEPROP 2 LAST ROOM BMC_DEBUG_HEADER
J 0
(-1950 2800);
DISPLAY 1.021277 (-1950 2800);
PAINT ORANGE (-1950 2800);
DISPLAY INVISIBLE (-1950 2800);
FORCEPROP 1 LAST PATH I22
J 0
(-1950 2850);
DISPLAY 0.978723 (-1950 2850);
PAINT WHITE (-1950 2850);
DISPLAY INVISIBLE (-1950 2850);
FORCEPROP 2 LAST SEC 1
J 0
(-1950 2900);
PAINT MONO (-1950 2900);
DISPLAY INVISIBLE (-1950 2900);
FORCEPROP 2 LAST SEC_TYPE 0402
J 0
(-1950 2900);
DISPLAY 1.021277 (-1950 2900);
PAINT ORANGE (-1950 2900);
DISPLAY INVISIBLE (-1950 2900);
FORCEPROP 2 LAST BOM_COST DEBUG
J 0
(-1950 2850);
DISPLAY 1.021277 (-1950 2850);
PAINT ORANGE (-1950 2850);
DISPLAY INVISIBLE (-1950 2850);
FORCEADD RES..1
(-1900 3075);
FORCEPROP 1 LAST VALUE 0.0
J 2
(-2075 3075);
DISPLAY 0.617021 (-2075 3075);
PAINT SKYBLUE (-2075 3075);
FORCEPROP 1 LAST WATTAGE 1/16W
J 2
(-1950 3025);
DISPLAY 0.617021 (-1950 3025);
PAINT SKYBLUE (-1950 3025);
FORCEPROP 1 LAST TOLERANCE 5%
J 0
(-2050 3075);
DISPLAY 0.617021 (-2050 3075);
PAINT SKYBLUE (-2050 3075);
FORCEPROP 1 LAST MATERIAL CHIP
J 0
(-1925 3025);
DISPLAY 0.617021 (-1925 3025);
PAINT SKYBLUE (-1925 3025);
FORCEPROP 1 LAST PACK_TYPE 0402
J 0
(-1825 3025);
DISPLAY 0.617021 (-1825 3025);
PAINT SKYBLUE (-1825 3025);
FORCEPROP 1 LASTPIN (-2000 3075) $PN 1
J 0
(-1988 3087);
DISPLAY 0.617021 (-1988 3087);
PAINT ORANGE (-1988 3087);
FORCEPROP 1 LAST LOCATION R8G13
J 0
(-1950 3125);
DISPLAY 0.617021 (-1950 3125);
PAINT AQUA (-1950 3125);
FORCEPROP 1 LASTPIN (-1800 3075) $PN 2
J 0
(-1838 3087);
DISPLAY 0.617021 (-1838 3087);
PAINT ORANGE (-1838 3087);
FORCEPROP 1 LAST PART_NUMBER G21497-005
J 0
(-1750 3075);
DISPLAY 0.617021 (-1750 3075);
PAINT BLUE (-1750 3075);
FORCEPROP 2 LAST CDS_LOCATION R8G13
J 0
(-1950 3125);
DISPLAY 0.617021 (-1950 3125);
PAINT AQUA (-1950 3125);
DISPLAY INVISIBLE (-1950 3125);
FORCEPROP 2 LAST ROOM BMC_DEBUG_HEADER
J 0
(-1950 3175);
DISPLAY 1.021277 (-1950 3175);
PAINT ORANGE (-1950 3175);
DISPLAY INVISIBLE (-1950 3175);
FORCEPROP 2 LAST SEC_TYPE 0402
J 0
(-1950 3275);
DISPLAY 1.021277 (-1950 3275);
PAINT ORANGE (-1950 3275);
DISPLAY INVISIBLE (-1950 3275);
FORCEPROP 2 LAST SEC 1
J 0
(-1950 3275);
DISPLAY 0.680851 (-1950 3275);
PAINT MONO (-1950 3275);
DISPLAY INVISIBLE (-1950 3275);
FORCEPROP 1 LAST PATH I23
J 0
(-1950 3225);
DISPLAY 0.978723 (-1950 3225);
PAINT WHITE (-1950 3225);
DISPLAY INVISIBLE (-1950 3225);
FORCEPROP 2 LAST BOM_COST DEBUG
J 0
(-1950 3225);
DISPLAY 1.021277 (-1950 3225);
PAINT ORANGE (-1950 3225);
DISPLAY INVISIBLE (-1950 3225);
FORCEPROP 2 LAST CDS_LIB mstr_discrete
J 0
(-1900 3075);
PAINT ORANGE (-1900 3075);
DISPLAY INVISIBLE (-1900 3075);
FORCEADD RES..1
(-1900 2875);
FORCEPROP 1 LAST VALUE 0.0
J 2
(-2075 2875);
DISPLAY 0.617021 (-2075 2875);
PAINT SKYBLUE (-2075 2875);
FORCEPROP 1 LAST WATTAGE 1/16W
J 2
(-1975 2825);
DISPLAY 0.617021 (-1975 2825);
PAINT SKYBLUE (-1975 2825);
FORCEPROP 1 LAST TOLERANCE 5%
J 0
(-2050 2875);
DISPLAY 0.617021 (-2050 2875);
PAINT SKYBLUE (-2050 2875);
FORCEPROP 1 LASTPIN (-2000 2875) $PN 1
J 0
(-1988 2887);
DISPLAY 0.617021 (-1988 2887);
PAINT ORANGE (-1988 2887);
FORCEPROP 1 LAST LOCATION R8G15
J 0
(-1950 2925);
DISPLAY 0.617021 (-1950 2925);
PAINT AQUA (-1950 2925);
FORCEPROP 1 LAST MATERIAL EMPTY
J 0
(-1950 2825);
DISPLAY 0.617021 (-1950 2825);
PAINT RED (-1950 2825);
FORCEPROP 1 LASTPIN (-1800 2875) $PN 2
J 0
(-1838 2887);
DISPLAY 0.617021 (-1838 2887);
PAINT ORANGE (-1838 2887);
FORCEPROP 1 LAST PACK_TYPE 0402
J 0
(-1800 2825);
DISPLAY 0.617021 (-1800 2825);
PAINT SKYBLUE (-1800 2825);
FORCEPROP 1 LAST PART_NUMBER G21497-005
J 0
(-1750 2875);
DISPLAY 0.617021 (-1750 2875);
PAINT BLUE (-1750 2875);
FORCEPROP 2 LAST CDS_LOCATION R8G15
J 0
(-1950 2925);
DISPLAY 0.617021 (-1950 2925);
PAINT AQUA (-1950 2925);
DISPLAY INVISIBLE (-1950 2925);
FORCEPROP 2 LAST ROOM BMC_DEBUG_HEADER
J 0
(-1950 2975);
DISPLAY 1.021277 (-1950 2975);
PAINT ORANGE (-1950 2975);
DISPLAY INVISIBLE (-1950 2975);
FORCEPROP 1 LAST PATH I24
J 0
(-1950 3025);
DISPLAY 0.978723 (-1950 3025);
PAINT WHITE (-1950 3025);
DISPLAY INVISIBLE (-1950 3025);
FORCEPROP 2 LAST BOM_COST DEBUG
J 0
(-1950 3025);
DISPLAY 1.021277 (-1950 3025);
PAINT ORANGE (-1950 3025);
DISPLAY INVISIBLE (-1950 3025);
FORCEPROP 2 LAST CDS_LIB mstr_discrete
J 0
(-1900 2875);
PAINT ORANGE (-1900 2875);
DISPLAY INVISIBLE (-1900 2875);
FORCEPROP 2 LAST SEC_TYPE 0402
J 0
(-1950 3075);
DISPLAY 1.021277 (-1950 3075);
PAINT ORANGE (-1950 3075);
DISPLAY INVISIBLE (-1950 3075);
FORCEPROP 2 LAST SEC 1
J 0
(-1950 3075);
DISPLAY 0.680851 (-1950 3075);
PAINT MONO (-1950 3075);
DISPLAY INVISIBLE (-1950 3075);
FORCEADD RES..1
(-1900 2525);
FORCEPROP 1 LAST VALUE 0.0
J 2
(-2075 2525);
DISPLAY 0.617021 (-2075 2525);
PAINT SKYBLUE (-2075 2525);
FORCEPROP 1 LAST WATTAGE 1/16W
J 2
(-1975 2475);
DISPLAY 0.617021 (-1975 2475);
PAINT SKYBLUE (-1975 2475);
FORCEPROP 1 LAST TOLERANCE 5%
J 0
(-2050 2525);
DISPLAY 0.617021 (-2050 2525);
PAINT SKYBLUE (-2050 2525);
FORCEPROP 1 LAST MATERIAL CHIP
J 0
(-1950 2475);
DISPLAY 0.617021 (-1950 2475);
PAINT SKYBLUE (-1950 2475);
FORCEPROP 1 LAST PACK_TYPE 0402
J 0
(-1825 2475);
DISPLAY 0.617021 (-1825 2475);
PAINT SKYBLUE (-1825 2475);
FORCEPROP 1 LASTPIN (-2000 2525) $PN 1
J 0
(-1988 2537);
DISPLAY 0.617021 (-1988 2537);
PAINT ORANGE (-1988 2537);
FORCEPROP 1 LASTPIN (-1800 2525) $PN 2
J 0
(-1838 2537);
DISPLAY 0.617021 (-1838 2537);
PAINT ORANGE (-1838 2537);
FORCEPROP 1 LAST LOCATION R8G17
J 0
(-1950 2575);
DISPLAY 0.617021 (-1950 2575);
PAINT AQUA (-1950 2575);
FORCEPROP 1 LAST PART_NUMBER G21497-005
J 0
(-1750 2525);
DISPLAY 0.617021 (-1750 2525);
PAINT BLUE (-1750 2525);
FORCEPROP 2 LAST CDS_LIB mstr_discrete
J 0
(-1900 2525);
PAINT ORANGE (-1900 2525);
DISPLAY INVISIBLE (-1900 2525);
FORCEPROP 2 LAST ROOM BMC_DEBUG_HEADER
J 0
(-1950 2625);
DISPLAY 1.021277 (-1950 2625);
PAINT ORANGE (-1950 2625);
DISPLAY INVISIBLE (-1950 2625);
FORCEPROP 2 LAST CDS_LOCATION R8G17
J 0
(-1950 2575);
DISPLAY 0.617021 (-1950 2575);
PAINT AQUA (-1950 2575);
DISPLAY INVISIBLE (-1950 2575);
FORCEPROP 1 LAST PATH I25
J 0
(-1950 2675);
DISPLAY 0.978723 (-1950 2675);
PAINT WHITE (-1950 2675);
DISPLAY INVISIBLE (-1950 2675);
FORCEPROP 2 LAST BOM_COST DEBUG
J 0
(-1950 2675);
DISPLAY 1.021277 (-1950 2675);
PAINT ORANGE (-1950 2675);
DISPLAY INVISIBLE (-1950 2675);
FORCEPROP 2 LAST SEC 1
J 0
(-1950 2725);
DISPLAY 0.680851 (-1950 2725);
PAINT MONO (-1950 2725);
DISPLAY INVISIBLE (-1950 2725);
FORCEPROP 2 LAST SEC_TYPE 0402
J 0
(-1950 2725);
DISPLAY 1.021277 (-1950 2725);
PAINT ORANGE (-1950 2725);
DISPLAY INVISIBLE (-1950 2725);
FORCEADD RES..1
(-1900 2350);
FORCEPROP 1 LAST VALUE 0.0
J 2
(-2075 2350);
DISPLAY 0.617021 (-2075 2350);
PAINT SKYBLUE (-2075 2350);
FORCEPROP 1 LAST WATTAGE 1/16W
J 2
(-1950 2300);
DISPLAY 0.617021 (-1950 2300);
PAINT SKYBLUE (-1950 2300);
FORCEPROP 1 LAST TOLERANCE 5%
J 0
(-2050 2350);
DISPLAY 0.617021 (-2050 2350);
PAINT SKYBLUE (-2050 2350);
FORCEPROP 1 LAST MATERIAL CHIP
J 0
(-1925 2300);
DISPLAY 0.617021 (-1925 2300);
PAINT SKYBLUE (-1925 2300);
FORCEPROP 1 LASTPIN (-2000 2350) $PN 1
J 0
(-1988 2362);
DISPLAY 0.617021 (-1988 2362);
PAINT ORANGE (-1988 2362);
FORCEPROP 1 LAST LOCATION R8G18
J 0
(-1950 2400);
DISPLAY 0.617021 (-1950 2400);
PAINT AQUA (-1950 2400);
FORCEPROP 1 LASTPIN (-1800 2350) $PN 2
J 0
(-1838 2362);
DISPLAY 0.617021 (-1838 2362);
PAINT ORANGE (-1838 2362);
FORCEPROP 1 LAST PACK_TYPE 0402
J 0
(-1825 2300);
DISPLAY 0.617021 (-1825 2300);
PAINT SKYBLUE (-1825 2300);
FORCEPROP 1 LAST PART_NUMBER G21497-005
J 0
(-1750 2350);
DISPLAY 0.617021 (-1750 2350);
PAINT BLUE (-1750 2350);
FORCEPROP 2 LAST CDS_LOCATION R8G18
J 0
(-1950 2400);
DISPLAY 0.617021 (-1950 2400);
PAINT AQUA (-1950 2400);
DISPLAY INVISIBLE (-1950 2400);
FORCEPROP 2 LAST BOM_COST DEBUG
J 0
(-1950 2500);
DISPLAY 1.021277 (-1950 2500);
PAINT ORANGE (-1950 2500);
DISPLAY INVISIBLE (-1950 2500);
FORCEPROP 1 LAST PATH I26
J 0
(-1950 2500);
DISPLAY 0.978723 (-1950 2500);
PAINT WHITE (-1950 2500);
DISPLAY INVISIBLE (-1950 2500);
FORCEPROP 2 LAST ROOM BMC_DEBUG_HEADER
J 0
(-1950 2450);
DISPLAY 1.021277 (-1950 2450);
PAINT ORANGE (-1950 2450);
DISPLAY INVISIBLE (-1950 2450);
FORCEPROP 2 LAST CDS_LIB mstr_discrete
J 0
(-1900 2350);
PAINT ORANGE (-1900 2350);
DISPLAY INVISIBLE (-1900 2350);
FORCEPROP 2 LAST SEC 1
J 0
(-1950 2550);
DISPLAY 0.680851 (-1950 2550);
PAINT MONO (-1950 2550);
DISPLAY INVISIBLE (-1950 2550);
FORCEPROP 2 LAST SEC_TYPE 0402
J 0
(-1950 2550);
DISPLAY 1.021277 (-1950 2550);
PAINT ORANGE (-1950 2550);
DISPLAY INVISIBLE (-1950 2550);
FORCEADD RES..1
(-1900 2150);
FORCEPROP 1 LAST VALUE 0.0
J 2
(-2075 2150);
DISPLAY 0.617021 (-2075 2150);
PAINT SKYBLUE (-2075 2150);
FORCEPROP 1 LAST WATTAGE 1/16W
J 2
(-1975 2100);
DISPLAY 0.617021 (-1975 2100);
PAINT SKYBLUE (-1975 2100);
FORCEPROP 1 LAST TOLERANCE 5%
J 0
(-2050 2150);
DISPLAY 0.617021 (-2050 2150);
PAINT SKYBLUE (-2050 2150);
FORCEPROP 1 LASTPIN (-2000 2150) $PN 1
J 0
(-1988 2162);
DISPLAY 0.617021 (-1988 2162);
PAINT ORANGE (-1988 2162);
FORCEPROP 1 LAST LOCATION R7G16
J 0
(-1950 2200);
DISPLAY 0.617021 (-1950 2200);
PAINT AQUA (-1950 2200);
FORCEPROP 1 LAST MATERIAL EMPTY
J 0
(-1950 2100);
DISPLAY 0.617021 (-1950 2100);
PAINT RED (-1950 2100);
FORCEPROP 1 LASTPIN (-1800 2150) $PN 2
J 0
(-1838 2162);
DISPLAY 0.617021 (-1838 2162);
PAINT ORANGE (-1838 2162);
FORCEPROP 1 LAST PACK_TYPE 0402
J 0
(-1800 2100);
DISPLAY 0.617021 (-1800 2100);
PAINT SKYBLUE (-1800 2100);
FORCEPROP 1 LAST PART_NUMBER G21497-005
J 0
(-1750 2150);
DISPLAY 0.617021 (-1750 2150);
PAINT BLUE (-1750 2150);
FORCEPROP 2 LAST ROOM BMC_DEBUG_HEADER
J 0
(-1950 2250);
DISPLAY 1.021277 (-1950 2250);
PAINT ORANGE (-1950 2250);
DISPLAY INVISIBLE (-1950 2250);
FORCEPROP 2 LAST CDS_LOCATION R7G16
J 0
(-1950 2200);
DISPLAY 0.617021 (-1950 2200);
PAINT AQUA (-1950 2200);
DISPLAY INVISIBLE (-1950 2200);
FORCEPROP 2 LAST CDS_LIB mstr_discrete
J 0
(-1900 2150);
PAINT ORANGE (-1900 2150);
DISPLAY INVISIBLE (-1900 2150);
FORCEPROP 1 LAST PATH I27
J 0
(-1950 2300);
DISPLAY 0.978723 (-1950 2300);
PAINT WHITE (-1950 2300);
DISPLAY INVISIBLE (-1950 2300);
FORCEPROP 2 LAST BOM_COST DEBUG
J 0
(-1950 2300);
DISPLAY 1.021277 (-1950 2300);
PAINT ORANGE (-1950 2300);
DISPLAY INVISIBLE (-1950 2300);
FORCEPROP 2 LAST SEC_TYPE 0402
J 0
(-1950 2350);
DISPLAY 1.021277 (-1950 2350);
PAINT ORANGE (-1950 2350);
DISPLAY INVISIBLE (-1950 2350);
FORCEPROP 2 LAST SEC 1
J 0
(-1950 2350);
DISPLAY 0.680851 (-1950 2350);
PAINT MONO (-1950 2350);
DISPLAY INVISIBLE (-1950 2350);
FORCEADD OFFPAGE..1
(-2650 4125);
FORCEPROP 2 LAST $XR0 120 
J 0
(-2902 4125);
DISPLAY 0.638298 (-2902 4125);
PAINT MONO (-2902 4125);
FORCEPROP 1 LAST OFFPAGE TRUE
J 0
(-2325 4000);
DISPLAY 0.872340 (-2325 4000);
PAINT GREEN (-2325 4000);
DISPLAY INVISIBLE (-2325 4000);
FORCEPROP 1 LAST COMMENT_BODY TRUE
J 0
(-2525 4025);
DISPLAY 0.872340 (-2525 4025);
PAINT GREEN (-2525 4025);
DISPLAY INVISIBLE (-2525 4025);
FORCEPROP 2 LAST PATH I28
J 0
(-2900 4175);
DISPLAY 1.021277 (-2900 4175);
PAINT ORANGE (-2900 4175);
DISPLAY INVISIBLE (-2900 4175);
FORCEPROP 2 LAST CDS_LIB mstr_standard
J 0
(-2650 4125);
PAINT MONO (-2650 4125);
DISPLAY INVISIBLE (-2650 4125);
FORCEADD OFFPAGE..1
(-2650 3775);
FORCEPROP 2 LAST $XR0 191 
J 0
(-2902 3775);
DISPLAY 0.638298 (-2902 3775);
PAINT MONO (-2902 3775);
FORCEPROP 2 LAST PATH I29
J 0
(-2925 3825);
DISPLAY 1.021277 (-2925 3825);
PAINT ORANGE (-2925 3825);
DISPLAY INVISIBLE (-2925 3825);
FORCEPROP 2 LAST CDS_LIB mstr_standard
J 0
(-2650 3775);
PAINT ORANGE (-2650 3775);
DISPLAY INVISIBLE (-2650 3775);
FORCEPROP 1 LAST OFFPAGE TRUE
J 0
(-2325 3650);
DISPLAY 0.872340 (-2325 3650);
PAINT GREEN (-2325 3650);
DISPLAY INVISIBLE (-2325 3650);
FORCEPROP 1 LAST COMMENT_BODY TRUE
J 0
(-2525 3675);
DISPLAY 0.872340 (-2525 3675);
PAINT GREEN (-2525 3675);
DISPLAY INVISIBLE (-2525 3675);
FORCEADD OFFPAGE..1
(-2650 3250);
FORCEPROP 2 LAST $XR0 144 
J 0
(-2902 3250);
DISPLAY 0.638298 (-2902 3250);
PAINT MONO (-2902 3250);
FORCEPROP 2 LAST PATH I3
J 0
(-2925 3300);
DISPLAY 1.021277 (-2925 3300);
PAINT ORANGE (-2925 3300);
DISPLAY INVISIBLE (-2925 3300);
FORCEPROP 2 LAST CDS_LIB mstr_standard
J 0
(-2650 3250);
PAINT ORANGE (-2650 3250);
DISPLAY INVISIBLE (-2650 3250);
FORCEPROP 1 LAST OFFPAGE TRUE
J 0
(-2325 3125);
DISPLAY 0.872340 (-2325 3125);
PAINT GREEN (-2325 3125);
DISPLAY INVISIBLE (-2325 3125);
FORCEPROP 1 LAST COMMENT_BODY TRUE
J 0
(-2525 3150);
DISPLAY 0.872340 (-2525 3150);
PAINT GREEN (-2525 3150);
DISPLAY INVISIBLE (-2525 3150);
FORCEADD OFFPAGE..1
(-2650 3950);
FORCEPROP 2 LAST $XR0 144 
J 0
(-2902 3950);
DISPLAY 0.638298 (-2902 3950);
PAINT MONO (-2902 3950);
FORCEPROP 2 LAST PATH I30
J 0
(-2900 4000);
DISPLAY 1.021277 (-2900 4000);
PAINT ORANGE (-2900 4000);
DISPLAY INVISIBLE (-2900 4000);
FORCEPROP 2 LAST CDS_LIB mstr_standard
J 0
(-2650 3950);
PAINT ORANGE (-2650 3950);
DISPLAY INVISIBLE (-2650 3950);
FORCEPROP 1 LAST OFFPAGE TRUE
J 0
(-2325 3825);
DISPLAY 0.872340 (-2325 3825);
PAINT GREEN (-2325 3825);
DISPLAY INVISIBLE (-2325 3825);
FORCEPROP 1 LAST COMMENT_BODY TRUE
J 0
(-2525 3850);
DISPLAY 0.872340 (-2525 3850);
PAINT GREEN (-2525 3850);
DISPLAY INVISIBLE (-2525 3850);
FORCEADD OFFPAGE..1
(-2650 3575);
FORCEPROP 2 LAST $XR0 120 
J 0
(-2902 3575);
DISPLAY 0.638298 (-2902 3575);
PAINT MONO (-2902 3575);
FORCEPROP 2 LAST CDS_LIB mstr_standard
J 0
(-2650 3575);
PAINT ORANGE (-2650 3575);
DISPLAY INVISIBLE (-2650 3575);
FORCEPROP 2 LAST PATH I31
J 0
(-2925 3625);
DISPLAY 1.021277 (-2925 3625);
PAINT ORANGE (-2925 3625);
DISPLAY INVISIBLE (-2925 3625);
FORCEPROP 1 LAST OFFPAGE TRUE
J 0
(-2325 3450);
DISPLAY 0.872340 (-2325 3450);
PAINT GREEN (-2325 3450);
DISPLAY INVISIBLE (-2325 3450);
FORCEPROP 1 LAST COMMENT_BODY TRUE
J 0
(-2525 3475);
DISPLAY 0.872340 (-2525 3475);
PAINT GREEN (-2525 3475);
DISPLAY INVISIBLE (-2525 3475);
FORCEADD OFFPAGE..1
(-2650 2700);
FORCEPROP 2 LAST $XR0 120 
J 0
(-2902 2700);
DISPLAY 0.638298 (-2902 2700);
PAINT MONO (-2902 2700);
FORCEPROP 2 LAST PATH I32
J 0
(-2925 2750);
DISPLAY 1.021277 (-2925 2750);
PAINT ORANGE (-2925 2750);
DISPLAY INVISIBLE (-2925 2750);
FORCEPROP 2 LAST CDS_LIB mstr_standard
J 0
(-2650 2700);
PAINT MONO (-2650 2700);
DISPLAY INVISIBLE (-2650 2700);
FORCEPROP 1 LAST COMMENT_BODY TRUE
J 0
(-2525 2600);
DISPLAY 0.872340 (-2525 2600);
PAINT GREEN (-2525 2600);
DISPLAY INVISIBLE (-2525 2600);
FORCEPROP 1 LAST OFFPAGE TRUE
J 0
(-2325 2575);
DISPLAY 0.872340 (-2325 2575);
PAINT GREEN (-2325 2575);
DISPLAY INVISIBLE (-2325 2575);
FORCEADD OFFPAGE..5
(-2650 2150);
FORCEPROP 2 LAST $XR0 120 
J 0
(-2905 2150);
DISPLAY 0.638298 (-2905 2150);
PAINT MONO (-2905 2150);
FORCEPROP 1 LAST OFFPAGE TRUE
J 0
(-2325 2025);
DISPLAY 0.872340 (-2325 2025);
PAINT GREEN (-2325 2025);
DISPLAY INVISIBLE (-2325 2025);
FORCEPROP 2 LAST PATH I33
J 0
(-2925 2200);
DISPLAY 1.021277 (-2925 2200);
PAINT ORANGE (-2925 2200);
DISPLAY INVISIBLE (-2925 2200);
FORCEPROP 2 LAST CDS_LIB mstr_standard
J 0
(-2650 2150);
PAINT ORANGE (-2650 2150);
DISPLAY INVISIBLE (-2650 2150);
FORCEPROP 1 LAST COMMENT_BODY TRUE
J 0
(-2550 2075);
DISPLAY 0.872340 (-2550 2075);
PAINT GREEN (-2550 2075);
DISPLAY INVISIBLE (-2550 2075);
FORCEADD OFFPAGE..1
(-2650 2525);
FORCEPROP 2 LAST $XR0 144 
J 0
(-2902 2525);
DISPLAY 0.638298 (-2902 2525);
PAINT MONO (-2902 2525);
FORCEPROP 2 LAST CDS_LIB mstr_standard
J 0
(-2650 2525);
PAINT ORANGE (-2650 2525);
DISPLAY INVISIBLE (-2650 2525);
FORCEPROP 2 LAST PATH I34
J 0
(-2925 2575);
DISPLAY 1.021277 (-2925 2575);
PAINT ORANGE (-2925 2575);
DISPLAY INVISIBLE (-2925 2575);
FORCEPROP 1 LAST COMMENT_BODY TRUE
J 0
(-2525 2425);
DISPLAY 0.872340 (-2525 2425);
PAINT GREEN (-2525 2425);
DISPLAY INVISIBLE (-2525 2425);
FORCEPROP 1 LAST OFFPAGE TRUE
J 0
(-2325 2400);
DISPLAY 0.872340 (-2325 2400);
PAINT GREEN (-2325 2400);
DISPLAY INVISIBLE (-2325 2400);
FORCEADD OFFPAGE..1
(-2650 2350);
FORCEPROP 2 LAST $XR0 191 
J 0
(-2902 2350);
DISPLAY 0.638298 (-2902 2350);
PAINT MONO (-2902 2350);
FORCEPROP 2 LAST PATH I35
J 0
(-2925 2400);
DISPLAY 1.021277 (-2925 2400);
PAINT ORANGE (-2925 2400);
DISPLAY INVISIBLE (-2925 2400);
FORCEPROP 2 LAST CDS_LIB mstr_standard
J 0
(-2650 2350);
PAINT ORANGE (-2650 2350);
DISPLAY INVISIBLE (-2650 2350);
FORCEPROP 1 LAST COMMENT_BODY TRUE
J 0
(-2525 2250);
DISPLAY 0.872340 (-2525 2250);
PAINT GREEN (-2525 2250);
DISPLAY INVISIBLE (-2525 2250);
FORCEPROP 1 LAST OFFPAGE TRUE
J 0
(-2325 2225);
DISPLAY 0.872340 (-2325 2225);
PAINT GREEN (-2325 2225);
DISPLAY INVISIBLE (-2325 2225);
FORCEADD RES..1
(-1900 1975);
FORCEPROP 1 LAST VALUE 0.0
J 2
(-2075 1975);
DISPLAY 0.617021 (-2075 1975);
PAINT SKYBLUE (-2075 1975);
FORCEPROP 1 LAST WATTAGE 1/16W
J 2
(-1975 1925);
DISPLAY 0.617021 (-1975 1925);
PAINT SKYBLUE (-1975 1925);
FORCEPROP 1 LAST TOLERANCE 5%
J 0
(-2050 1975);
DISPLAY 0.617021 (-2050 1975);
PAINT SKYBLUE (-2050 1975);
FORCEPROP 1 LASTPIN (-2000 1975) $PN 1
J 0
(-1988 1987);
DISPLAY 0.617021 (-1988 1987);
PAINT ORANGE (-1988 1987);
FORCEPROP 1 LAST MATERIAL EMPTY
J 0
(-1950 1925);
DISPLAY 0.617021 (-1950 1925);
PAINT RED (-1950 1925);
FORCEPROP 1 LASTPIN (-1800 1975) $PN 2
J 0
(-1838 1987);
DISPLAY 0.617021 (-1838 1987);
PAINT ORANGE (-1838 1987);
FORCEPROP 1 LAST PACK_TYPE 0402
J 0
(-1800 1925);
DISPLAY 0.617021 (-1800 1925);
PAINT SKYBLUE (-1800 1925);
FORCEPROP 1 LAST PART_NUMBER G21497-005
J 0
(-1750 1975);
DISPLAY 0.617021 (-1750 1975);
PAINT BLUE (-1750 1975);
FORCEPROP 1 LAST LOCATION R7G15
J 0
(-1950 2025);
DISPLAY 0.617021 (-1950 2025);
PAINT AQUA (-1950 2025);
FORCEPROP 2 LAST CDS_LIB mstr_discrete
J 0
(-1900 1975);
PAINT MONO (-1900 1975);
DISPLAY INVISIBLE (-1900 1975);
FORCEPROP 2 LAST CDS_LOCATION R7G15
J 0
(-1950 2025);
DISPLAY 0.617021 (-1950 2025);
PAINT AQUA (-1950 2025);
DISPLAY INVISIBLE (-1950 2025);
FORCEPROP 2 LAST ROOM BMC_DEBUG_HEADER
J 0
(-1950 2075);
DISPLAY 1.021277 (-1950 2075);
PAINT ORANGE (-1950 2075);
DISPLAY INVISIBLE (-1950 2075);
FORCEPROP 1 LAST PATH I36
J 0
(-1950 2125);
DISPLAY 0.978723 (-1950 2125);
PAINT WHITE (-1950 2125);
DISPLAY INVISIBLE (-1950 2125);
FORCEPROP 2 LAST BOM_COST DEBUG
J 0
(-1950 2125);
DISPLAY 1.021277 (-1950 2125);
PAINT ORANGE (-1950 2125);
DISPLAY INVISIBLE (-1950 2125);
FORCEPROP 2 LAST SEC 1
J 0
(-1950 2175);
PAINT MONO (-1950 2175);
DISPLAY INVISIBLE (-1950 2175);
FORCEPROP 2 LAST SEC_TYPE 0402
J 0
(-1950 2175);
DISPLAY 1.021277 (-1950 2175);
PAINT ORANGE (-1950 2175);
DISPLAY INVISIBLE (-1950 2175);
FORCEADD RES..1
(-1900 1800);
FORCEPROP 1 LAST VALUE 0.0
J 2
(-2075 1800);
DISPLAY 0.617021 (-2075 1800);
PAINT SKYBLUE (-2075 1800);
FORCEPROP 1 LAST WATTAGE 1/16W
J 2
(-1975 1750);
DISPLAY 0.617021 (-1975 1750);
PAINT SKYBLUE (-1975 1750);
FORCEPROP 1 LAST TOLERANCE 5%
J 0
(-2050 1800);
DISPLAY 0.617021 (-2050 1800);
PAINT SKYBLUE (-2050 1800);
FORCEPROP 1 LAST MATERIAL CHIP
J 0
(-1950 1750);
DISPLAY 0.617021 (-1950 1750);
PAINT SKYBLUE (-1950 1750);
FORCEPROP 1 LASTPIN (-2000 1800) $PN 1
J 0
(-1988 1812);
DISPLAY 0.617021 (-1988 1812);
PAINT ORANGE (-1988 1812);
FORCEPROP 1 LAST LOCATION R7G17
J 0
(-1950 1850);
DISPLAY 0.617021 (-1950 1850);
PAINT AQUA (-1950 1850);
FORCEPROP 1 LASTPIN (-1800 1800) $PN 2
J 0
(-1838 1812);
DISPLAY 0.617021 (-1838 1812);
PAINT ORANGE (-1838 1812);
FORCEPROP 1 LAST PACK_TYPE 0402
J 0
(-1800 1750);
DISPLAY 0.617021 (-1800 1750);
PAINT SKYBLUE (-1800 1750);
FORCEPROP 1 LAST PART_NUMBER G21497-005
J 0
(-1950 1900);
DISPLAY 0.617021 (-1950 1900);
PAINT BLUE (-1950 1900);
FORCEPROP 2 LAST CDS_LOCATION R7G17
J 0
(-1950 1850);
DISPLAY 0.617021 (-1950 1850);
PAINT AQUA (-1950 1850);
DISPLAY INVISIBLE (-1950 1850);
FORCEPROP 2 LAST ROOM BMC_DEBUG_HEADER
J 0
(-1950 1900);
DISPLAY 1.021277 (-1950 1900);
PAINT ORANGE (-1950 1900);
DISPLAY INVISIBLE (-1950 1900);
FORCEPROP 1 LAST PATH I37
J 0
(-1950 1950);
DISPLAY 0.978723 (-1950 1950);
PAINT WHITE (-1950 1950);
DISPLAY INVISIBLE (-1950 1950);
FORCEPROP 2 LAST SEC 1
J 0
(-1950 2000);
DISPLAY 0.680851 (-1950 2000);
PAINT MONO (-1950 2000);
DISPLAY INVISIBLE (-1950 2000);
FORCEPROP 2 LAST BOM_COST DEBUG
J 0
(-1950 1950);
DISPLAY 1.021277 (-1950 1950);
PAINT ORANGE (-1950 1950);
DISPLAY INVISIBLE (-1950 1950);
FORCEPROP 2 LAST SEC_TYPE 0402
J 0
(-1950 2000);
DISPLAY 1.021277 (-1950 2000);
PAINT ORANGE (-1950 2000);
DISPLAY INVISIBLE (-1950 2000);
FORCEPROP 2 LAST CDS_LIB mstr_discrete
J 0
(-1900 1800);
PAINT ORANGE (-1900 1800);
DISPLAY INVISIBLE (-1900 1800);
FORCEADD RES..1
(-1900 1625);
FORCEPROP 1 LAST VALUE 0.0
J 2
(-2075 1625);
DISPLAY 0.617021 (-2075 1625);
PAINT SKYBLUE (-2075 1625);
FORCEPROP 1 LAST WATTAGE 1/16W
J 2
(-1950 1575);
DISPLAY 0.617021 (-1950 1575);
PAINT SKYBLUE (-1950 1575);
FORCEPROP 1 LAST TOLERANCE 5%
J 0
(-2050 1625);
DISPLAY 0.617021 (-2050 1625);
PAINT SKYBLUE (-2050 1625);
FORCEPROP 1 LASTPIN (-2000 1625) $PN 1
J 0
(-1988 1637);
DISPLAY 0.617021 (-1988 1637);
PAINT ORANGE (-1988 1637);
FORCEPROP 1 LAST MATERIAL CHIP
J 0
(-1925 1575);
DISPLAY 0.617021 (-1925 1575);
PAINT SKYBLUE (-1925 1575);
FORCEPROP 1 LAST LOCATION R7G14
J 0
(-1950 1675);
DISPLAY 0.617021 (-1950 1675);
PAINT AQUA (-1950 1675);
FORCEPROP 1 LASTPIN (-1800 1625) $PN 2
J 0
(-1838 1637);
DISPLAY 0.617021 (-1838 1637);
PAINT ORANGE (-1838 1637);
FORCEPROP 1 LAST PACK_TYPE 0402
J 0
(-1825 1575);
DISPLAY 0.617021 (-1825 1575);
PAINT SKYBLUE (-1825 1575);
FORCEPROP 1 LAST PART_NUMBER G21497-005
J 0
(-1750 1625);
DISPLAY 0.617021 (-1750 1625);
PAINT BLUE (-1750 1625);
FORCEPROP 2 LAST CDS_LOCATION R7G14
J 0
(-1950 1675);
DISPLAY 0.617021 (-1950 1675);
PAINT AQUA (-1950 1675);
DISPLAY INVISIBLE (-1950 1675);
FORCEPROP 2 LAST ROOM BMC_DEBUG_HEADER
J 0
(-1950 1725);
DISPLAY 1.021277 (-1950 1725);
PAINT ORANGE (-1950 1725);
DISPLAY INVISIBLE (-1950 1725);
FORCEPROP 2 LAST CDS_LIB mstr_discrete
J 0
(-1900 1625);
PAINT ORANGE (-1900 1625);
DISPLAY INVISIBLE (-1900 1625);
FORCEPROP 1 LAST PATH I38
J 0
(-1950 1775);
DISPLAY 0.978723 (-1950 1775);
PAINT WHITE (-1950 1775);
DISPLAY INVISIBLE (-1950 1775);
FORCEPROP 2 LAST BOM_COST DEBUG
J 0
(-1950 1775);
DISPLAY 1.021277 (-1950 1775);
PAINT ORANGE (-1950 1775);
DISPLAY INVISIBLE (-1950 1775);
FORCEPROP 2 LAST SEC 1
J 0
(-1950 1825);
DISPLAY 0.680851 (-1950 1825);
PAINT MONO (-1950 1825);
DISPLAY INVISIBLE (-1950 1825);
FORCEPROP 2 LAST SEC_TYPE 0402
J 0
(-1950 1825);
DISPLAY 1.021277 (-1950 1825);
PAINT ORANGE (-1950 1825);
DISPLAY INVISIBLE (-1950 1825);
FORCEADD OFFPAGE..5
(-2650 1975);
FORCEPROP 2 LAST $XR0 120 
J 0
(-2905 1975);
DISPLAY 0.638298 (-2905 1975);
PAINT MONO (-2905 1975);
FORCEPROP 2 LAST CDS_LIB mstr_standard
J 0
(-2650 1975);
PAINT MONO (-2650 1975);
DISPLAY INVISIBLE (-2650 1975);
FORCEPROP 1 LAST COMMENT_BODY TRUE
J 0
(-2550 1900);
DISPLAY 0.872340 (-2550 1900);
PAINT GREEN (-2550 1900);
DISPLAY INVISIBLE (-2550 1900);
FORCEPROP 1 LAST OFFPAGE TRUE
J 0
(-2325 1850);
DISPLAY 0.872340 (-2325 1850);
PAINT GREEN (-2325 1850);
DISPLAY INVISIBLE (-2325 1850);
FORCEPROP 2 LAST PATH I39
J 0
(-2925 2025);
DISPLAY 1.021277 (-2925 2025);
PAINT ORANGE (-2925 2025);
DISPLAY INVISIBLE (-2925 2025);
FORCEADD OFFPAGE..1
(-2650 3400);
FORCEPROP 2 LAST $XR0 120 
J 0
(-2902 3400);
DISPLAY 0.638298 (-2902 3400);
PAINT MONO (-2902 3400);
FORCEPROP 2 LAST PATH I4
J 0
(-2925 3450);
DISPLAY 1.021277 (-2925 3450);
PAINT ORANGE (-2925 3450);
DISPLAY INVISIBLE (-2925 3450);
FORCEPROP 2 LAST CDS_LIB mstr_standard
J 0
(-2650 3400);
PAINT MONO (-2650 3400);
DISPLAY INVISIBLE (-2650 3400);
FORCEPROP 1 LAST OFFPAGE TRUE
J 0
(-2325 3275);
DISPLAY 0.872340 (-2325 3275);
PAINT GREEN (-2325 3275);
DISPLAY INVISIBLE (-2325 3275);
FORCEPROP 1 LAST COMMENT_BODY TRUE
J 0
(-2525 3300);
DISPLAY 0.872340 (-2525 3300);
PAINT GREEN (-2525 3300);
DISPLAY INVISIBLE (-2525 3300);
FORCEADD OFFPAGE..5
(-2650 1625);
FORCEPROP 2 LAST $XR0 191 
J 0
(-2905 1625);
DISPLAY 0.638298 (-2905 1625);
PAINT MONO (-2905 1625);
FORCEPROP 2 LAST PATH I40
J 0
(-2925 1675);
DISPLAY 1.021277 (-2925 1675);
PAINT ORANGE (-2925 1675);
DISPLAY INVISIBLE (-2925 1675);
FORCEPROP 2 LAST CDS_LIB mstr_standard
J 0
(-2650 1625);
PAINT ORANGE (-2650 1625);
DISPLAY INVISIBLE (-2650 1625);
FORCEPROP 1 LAST COMMENT_BODY TRUE
J 0
(-2550 1550);
DISPLAY 0.872340 (-2550 1550);
PAINT GREEN (-2550 1550);
DISPLAY INVISIBLE (-2550 1550);
FORCEPROP 1 LAST OFFPAGE TRUE
J 0
(-2325 1500);
DISPLAY 0.872340 (-2325 1500);
PAINT GREEN (-2325 1500);
DISPLAY INVISIBLE (-2325 1500);
FORCEADD OFFPAGE..5
(-2650 1800);
FORCEPROP 2 LAST $XR0 144 
J 0
(-2905 1800);
DISPLAY 0.638298 (-2905 1800);
PAINT MONO (-2905 1800);
FORCEPROP 2 LAST PATH I41
J 0
(-2925 1850);
DISPLAY 1.021277 (-2925 1850);
PAINT ORANGE (-2925 1850);
DISPLAY INVISIBLE (-2925 1850);
FORCEPROP 2 LAST CDS_LIB mstr_standard
J 0
(-2650 1800);
PAINT ORANGE (-2650 1800);
DISPLAY INVISIBLE (-2650 1800);
FORCEPROP 1 LAST COMMENT_BODY TRUE
J 0
(-2550 1725);
DISPLAY 0.872340 (-2550 1725);
PAINT GREEN (-2550 1725);
DISPLAY INVISIBLE (-2550 1725);
FORCEPROP 1 LAST OFFPAGE TRUE
J 0
(-2325 1675);
DISPLAY 0.872340 (-2325 1675);
PAINT GREEN (-2325 1675);
DISPLAY INVISIBLE (-2325 1675);
FORCEADD OFFPAGE..2
(675 1725);
FORCEPROP 2 LAST $XR0 191 
J 0
(864 1725);
DISPLAY 0.638298 (864 1725);
PAINT MONO (864 1725);
FORCEPROP 2 LASTPIN (625 1725) SIG_NAME FM_JTAG_PLD_EN_DEBUG
J 2
(615 1735);
DISPLAY 0.617021 (615 1735);
PAINT ORANGE (615 1735);
FORCEPROP 1 LAST COMMENT_BODY TRUE
J 0
(630 1630);
DISPLAY 0.872340 (630 1630);
PAINT GREEN (630 1630);
DISPLAY INVISIBLE (630 1630);
FORCEPROP 2 LAST CDS_LIB mstr_standard
J 0
(675 1725);
PAINT MONO (675 1725);
DISPLAY INVISIBLE (675 1725);
FORCEPROP 2 LAST PATH I42
J 0
(875 1775);
DISPLAY 1.021277 (875 1775);
PAINT ORANGE (875 1775);
DISPLAY INVISIBLE (875 1775);
FORCEPROP 1 LAST OFFPAGE TRUE
J 0
(1000 1600);
DISPLAY 0.872340 (1000 1600);
PAINT GREEN (1000 1600);
DISPLAY INVISIBLE (1000 1600);
FORCEADD P3V3_STBY..1
(-175 2125);
FORCEPROP 3 LASTPIN (-175 2075) SIG_NAME P3V3_STBY\g
J 0
(-165 2085);
DISPLAY 0.659574 (-165 2085);
PAINT MONO (-165 2085);
DISPLAY INVISIBLE (-165 2085);
FORCEPROP 1 LAST HDL_POWER P3V3_STBY
J 0
(-475 2000);
DISPLAY 0.872340 (-475 2000);
PAINT ORANGE (-475 2000);
DISPLAY INVISIBLE (-475 2000);
FORCEPROP 1 LAST PATH I43
J 0
(-130 2127);
DISPLAY 0.340426 (-130 2127);
PAINT GREEN (-130 2127);
DISPLAY INVISIBLE (-130 2127);
FORCEPROP 1 LAST VOLTAGE 3.3V
J 0
(-220 2082);
DISPLAY 0.340426 (-220 2082);
PAINT SKYBLUE (-220 2082);
DISPLAY INVISIBLE (-220 2082);
FORCEPROP 2 LAST CDS_LIB mstr_symbols
J 0
(-175 2125);
PAINT MONO (-175 2125);
DISPLAY INVISIBLE (-175 2125);
FORCEPROP 1 LAST SIZE 1B
J 0
(-130 2147);
DISPLAY 0.340426 (-130 2147);
PAINT GREEN (-130 2147);
DISPLAY INVISIBLE (-130 2147);
FORCEPROP 1 LAST BODY_TYPE PLUMBING
J 0
(-220 2082);
DISPLAY 0.340426 (-220 2082);
PAINT GREEN (-220 2082);
DISPLAY INVISIBLE (-220 2082);
FORCEADD RES..2
(-175 1925);
FORCEPROP 1 LAST PACK_TYPE 0402
J 0
(-135 1750);
DISPLAY 0.617021 (-135 1750);
PAINT SKYBLUE (-135 1750);
FORCEPROP 1 LASTPIN (-175 1825) $PN 2
J 0
(-170 1835);
DISPLAY 0.617021 (-170 1835);
PAINT ORANGE (-170 1835);
FORCEPROP 1 LASTPIN (-175 2025) $PN 1
J 0
(-170 1987);
DISPLAY 0.617021 (-170 1987);
PAINT ORANGE (-170 1987);
FORCEPROP 1 LAST TOLERANCE 1%
J 0
(-130 1950);
DISPLAY 0.617021 (-130 1950);
PAINT SKYBLUE (-130 1950);
FORCEPROP 1 LAST MATERIAL CHIP
J 0
(-135 1850);
DISPLAY 0.617021 (-135 1850);
PAINT SKYBLUE (-135 1850);
FORCEPROP 1 LAST WATTAGE 1/16W
J 0
(-135 1900);
DISPLAY 0.617021 (-135 1900);
PAINT SKYBLUE (-135 1900);
FORCEPROP 1 LAST VALUE 1.00K
J 0
(-130 2000);
DISPLAY 0.617021 (-130 2000);
PAINT SKYBLUE (-130 2000);
FORCEPROP 1 LAST PART_NUMBER G21796-026
J 0
(-135 1800);
DISPLAY 0.617021 (-135 1800);
PAINT BLUE (-135 1800);
FORCEPROP 1 LAST LOCATION R3R15
J 0
(-130 2050);
DISPLAY 0.617021 (-130 2050);
PAINT AQUA (-130 2050);
FORCEPROP 2 LAST CDS_LIB mstr_discrete
J 0
(-175 1925);
PAINT ORANGE (-175 1925);
DISPLAY INVISIBLE (-175 1925);
FORCEPROP 0 LAST ROOM BMC_DEBUG_HEADER
J 0
(-125 2150);
DISPLAY 1.021277 (-125 2150);
PAINT ORANGE (-125 2150);
DISPLAY INVISIBLE (-125 2150);
FORCEPROP 1 LAST PATH I44
J 0
(-125 2100);
DISPLAY 0.978723 (-125 2100);
PAINT WHITE (-125 2100);
DISPLAY INVISIBLE (-125 2100);
FORCEPROP 2 LAST CDS_LOCATION R3R15
J 0
(-130 2050);
DISPLAY 0.617021 (-130 2050);
PAINT AQUA (-130 2050);
DISPLAY INVISIBLE (-130 2050);
FORCEPROP 2 LAST SEC 1
J 0
(-125 2150);
DISPLAY 0.680851 (-125 2150);
PAINT MONO (-125 2150);
DISPLAY INVISIBLE (-125 2150);
FORCEPROP 2 LAST SEC_TYPE 0402
J 0
(-125 2150);
DISPLAY 1.021277 (-125 2150);
PAINT ORANGE (-125 2150);
DISPLAY INVISIBLE (-125 2150);
FORCEADD RES..2
(-175 1525);
FORCEPROP 1 LAST PACK_TYPE 0402
J 0
(-135 1350);
DISPLAY 0.617021 (-135 1350);
PAINT SKYBLUE (-135 1350);
FORCEPROP 1 LASTPIN (-175 1625) $PN 1
J 0
(-170 1587);
DISPLAY 0.617021 (-170 1587);
PAINT ORANGE (-170 1587);
FORCEPROP 1 LAST PART_NUMBER G21796-016
J 0
(-135 1400);
DISPLAY 0.617021 (-135 1400);
PAINT BLUE (-135 1400);
FORCEPROP 1 LAST LOCATION R3R11
J 0
(-130 1650);
DISPLAY 0.617021 (-130 1650);
PAINT AQUA (-130 1650);
FORCEPROP 1 LAST MATERIAL EMPTY
J 0
(-135 1450);
DISPLAY 0.617021 (-135 1450);
PAINT RED (-135 1450);
FORCEPROP 1 LASTPIN (-175 1425) $PN 2
J 0
(-170 1435);
DISPLAY 0.617021 (-170 1435);
PAINT ORANGE (-170 1435);
FORCEPROP 1 LAST WATTAGE 1/16W
J 0
(-135 1500);
DISPLAY 0.617021 (-135 1500);
PAINT SKYBLUE (-135 1500);
FORCEPROP 1 LAST TOLERANCE 1%
J 0
(-130 1550);
DISPLAY 0.617021 (-130 1550);
PAINT SKYBLUE (-130 1550);
FORCEPROP 1 LAST VALUE 10.0K
J 0
(-130 1600);
DISPLAY 0.617021 (-130 1600);
PAINT SKYBLUE (-130 1600);
FORCEPROP 2 LAST CDS_LIB mstr_discrete
J 0
(-175 1525);
PAINT ORANGE (-175 1525);
DISPLAY INVISIBLE (-175 1525);
FORCEPROP 2 LAST CDS_LOCATION R3R11
J 0
(-130 1650);
DISPLAY 0.617021 (-130 1650);
PAINT AQUA (-130 1650);
DISPLAY INVISIBLE (-130 1650);
FORCEPROP 1 LAST PATH I45
J 0
(-125 1700);
DISPLAY 0.978723 (-125 1700);
PAINT WHITE (-125 1700);
DISPLAY INVISIBLE (-125 1700);
FORCEPROP 2 LAST SEC 1
J 0
(-125 1750);
DISPLAY 0.680851 (-125 1750);
PAINT MONO (-125 1750);
DISPLAY INVISIBLE (-125 1750);
FORCEPROP 0 LAST ROOM BMC_DEBUG_HEADER
J 0
(-125 1750);
DISPLAY 1.021277 (-125 1750);
PAINT ORANGE (-125 1750);
DISPLAY INVISIBLE (-125 1750);
FORCEPROP 2 LAST SEC_TYPE 0402
J 0
(-125 1750);
DISPLAY 1.021277 (-125 1750);
PAINT ORANGE (-125 1750);
DISPLAY INVISIBLE (-125 1750);
FORCEADD GND..1
(-175 1325);
FORCEPROP 3 LASTPIN (-175 1375) SIG_NAME GND\g
J 0
(-165 1385);
DISPLAY 0.659574 (-165 1385);
PAINT MONO (-165 1385);
DISPLAY INVISIBLE (-165 1385);
FORCEPROP 1 LAST SIZE 1B
J 0
(-100 1275);
DISPLAY 0.872340 (-100 1275);
PAINT AQUA (-100 1275);
DISPLAY INVISIBLE (-100 1275);
FORCEPROP 1 LAST BODY_TYPE PLUMBING
J 0
(-220 1282);
DISPLAY 0.340426 (-220 1282);
PAINT GREEN (-220 1282);
DISPLAY INVISIBLE (-220 1282);
FORCEPROP 2 LAST CDS_LIB mstr_symbols
J 0
(-175 1325);
PAINT MONO (-175 1325);
DISPLAY INVISIBLE (-175 1325);
FORCEPROP 1 LAST VOLTAGE 0.0V
J 0
(-220 1282);
DISPLAY 0.340426 (-220 1282);
PAINT SKYBLUE (-220 1282);
DISPLAY INVISIBLE (-220 1282);
FORCEPROP 1 LAST HDL_POWER GND
J 0
(-175 1475);
DISPLAY 0.872340 (-175 1475);
PAINT GREEN (-175 1475);
DISPLAY INVISIBLE (-175 1475);
FORCEPROP 1 LAST PATH I46
J 0
(-100 1325);
DISPLAY 0.872340 (-100 1325);
PAINT AQUA (-100 1325);
DISPLAY INVISIBLE (-100 1325);
FORCEADD CONN8_C77962004..1
R 2
(3475 3625);
FORCEPROP 2 LASTPIN (3275 3425) $PN 8
J 2
(3265 3435);
DISPLAY 0.617021 (3265 3435);
PAINT ORANGE (3265 3435);
FORCEPROP 2 LASTPIN (3275 3475) $PN 7
J 2
(3265 3485);
DISPLAY 0.617021 (3265 3485);
PAINT ORANGE (3265 3485);
FORCEPROP 2 LASTPIN (3275 3525) $PN 6
J 2
(3265 3535);
DISPLAY 0.617021 (3265 3535);
PAINT ORANGE (3265 3535);
FORCEPROP 2 LASTPIN (3275 3575) $PN 5
J 2
(3265 3585);
DISPLAY 0.617021 (3265 3585);
PAINT ORANGE (3265 3585);
FORCEPROP 2 LASTPIN (3275 3625) $PN 4
J 2
(3265 3635);
DISPLAY 0.617021 (3265 3635);
PAINT ORANGE (3265 3635);
FORCEPROP 2 LASTPIN (3275 3675) $PN 3
J 2
(3265 3685);
DISPLAY 0.617021 (3265 3685);
PAINT ORANGE (3265 3685);
FORCEPROP 2 LASTPIN (3275 3725) $PN 2
J 2
(3265 3735);
DISPLAY 0.617021 (3265 3735);
PAINT ORANGE (3265 3735);
FORCEPROP 2 LASTPIN (3275 3775) $PN 1
J 2
(3265 3785);
DISPLAY 0.617021 (3265 3785);
PAINT ORANGE (3265 3785);
FORCEPROP 1 LAST LOCATION J7G2
J 2
(3575 4050);
DISPLAY 0.617021 (3575 4050);
PAINT AQUA (3575 4050);
FORCEPROP 1 LAST MATERIAL CONN
J 2
(3625 3975);
DISPLAY 0.617021 (3625 3975);
PAINT SKYBLUE (3625 3975);
FORCEPROP 1 LAST PART_NUMBER C77962-004
J 2
(3625 3275);
DISPLAY 0.617021 (3625 3275);
PAINT BLUE (3625 3275);
FORCEPROP 1 LAST PATH I47
J 2
(3175 3975);
PAINT GREEN (3175 3975);
DISPLAY INVISIBLE (3175 3975);
FORCEPROP 2 LAST CDS_LOCATION J7G2
J 2
(3575 4050);
DISPLAY 0.617021 (3575 4050);
PAINT AQUA (3575 4050);
DISPLAY INVISIBLE (3575 4050);
FORCEPROP 2 LAST CDS_LIB mstr_conn
J 0
(3475 3625);
PAINT ORANGE (3475 3625);
DISPLAY INVISIBLE (3475 3625);
FORCEPROP 1 LAST PACK_TYPE PIP
J 2
(3625 4075);
PAINT SKYBLUE (3625 4075);
DISPLAY INVISIBLE (3625 4075);
FORCEPROP 0 LAST ROOM BMC_DEBUG_HEADER
J 2
(3625 4100);
DISPLAY 1.021277 (3625 4100);
PAINT ORANGE (3625 4100);
DISPLAY INVISIBLE (3625 4100);
FORCEPROP 2 LAST SEC 1
J 0
(3575 4100);
DISPLAY 0.680851 (3575 4100);
PAINT MONO (3575 4100);
DISPLAY INVISIBLE (3575 4100);
FORCEPROP 2 LAST SEC_TYPE PIP
J 0
(3575 4100);
DISPLAY 1.021277 (3575 4100);
PAINT ORANGE (3575 4100);
DISPLAY INVISIBLE (3575 4100);
FORCEPROP 0 LAST BOM_COST DEBUG
J 2
(3625 4100);
DISPLAY 1.021277 (3625 4100);
PAINT ORANGE (3625 4100);
DISPLAY INVISIBLE (3625 4100);
FORCEADD P3V3_STBY..1
(2650 4350);
FORCEPROP 3 LASTPIN (2650 4300) SIG_NAME P3V3_STBY\g
J 0
(2660 4310);
DISPLAY 0.659574 (2660 4310);
PAINT MONO (2660 4310);
DISPLAY INVISIBLE (2660 4310);
FORCEPROP 1 LAST HDL_POWER P3V3_STBY
J 0
(2350 4225);
DISPLAY 0.872340 (2350 4225);
PAINT ORANGE (2350 4225);
DISPLAY INVISIBLE (2350 4225);
FORCEPROP 1 LAST BODY_TYPE PLUMBING
J 0
(2605 4307);
DISPLAY 0.340426 (2605 4307);
PAINT GREEN (2605 4307);
DISPLAY INVISIBLE (2605 4307);
FORCEPROP 1 LAST VOLTAGE 3.3V
J 0
(2605 4307);
DISPLAY 0.340426 (2605 4307);
PAINT SKYBLUE (2605 4307);
DISPLAY INVISIBLE (2605 4307);
FORCEPROP 1 LAST PATH I48
J 0
(2695 4352);
DISPLAY 0.340426 (2695 4352);
PAINT GREEN (2695 4352);
DISPLAY INVISIBLE (2695 4352);
FORCEPROP 2 LAST CDS_LIB mstr_symbols
J 0
(2650 4350);
PAINT MONO (2650 4350);
DISPLAY INVISIBLE (2650 4350);
FORCEPROP 1 LAST SIZE 1B
J 0
(2695 4372);
DISPLAY 0.340426 (2695 4372);
PAINT GREEN (2695 4372);
DISPLAY INVISIBLE (2695 4372);
FORCEADD DIODE..1
(2800 4050);
FORCEPROP 1 LASTPIN (2700 4050) $PN 2
J 2
(2735 4060);
DISPLAY 0.617021 (2735 4060);
PAINT AQUA (2735 4060);
FORCEPROP 1 LAST MATERIAL IC
J 0
(2775 3872);
DISPLAY 0.617021 (2775 3872);
PAINT SKYBLUE (2775 3872);
FORCEPROP 1 LASTPIN (2900 4050) $PN 1
J 0
(2865 4060);
DISPLAY 0.617021 (2865 4060);
PAINT AQUA (2865 4060);
FORCEPROP 1 LAST PART_NUMBER D55839-001
J 0
(2775 4150);
DISPLAY 0.617021 (2775 4150);
PAINT BLUE (2775 4150);
FORCEPROP 1 LAST PACK_TYPE SMLF
J 0
(2775 3810);
DISPLAY 0.617021 (2775 3810);
PAINT SKYBLUE (2775 3810);
FORCEPROP 1 LAST VALUE 1N5819HW
J 0
(2775 3925);
DISPLAY 0.617021 (2775 3925);
PAINT SKYBLUE (2775 3925);
FORCEPROP 1 LAST LOCATION CR3U1
J 0
(2773 4206);
DISPLAY 0.617021 (2773 4206);
PAINT AQUA (2773 4206);
FORCEPROP 2 LAST CDS_LIB mstr_discrete
J 0
(2800 4050);
PAINT MONO (2800 4050);
DISPLAY INVISIBLE (2800 4050);
FORCEPROP 1 LAST PATH I49
J 0
(2780 4260);
DISPLAY 0.978723 (2780 4260);
PAINT PINK (2780 4260);
DISPLAY INVISIBLE (2780 4260);
FORCEPROP 0 LAST ROOM BMC_DEBUG_HEADER
J 0
(2775 4300);
DISPLAY 1.021277 (2775 4300);
PAINT ORANGE (2775 4300);
DISPLAY INVISIBLE (2775 4300);
FORCEPROP 2 LAST SEC_TYPE SMLF
J 0
(2800 4325);
DISPLAY 1.021277 (2800 4325);
PAINT ORANGE (2800 4325);
DISPLAY INVISIBLE (2800 4325);
FORCEPROP 2 LAST SEC 1
J 0
(2800 4325);
DISPLAY 0.680851 (2800 4325);
PAINT MONO (2800 4325);
DISPLAY INVISIBLE (2800 4325);
FORCEPROP 0 LAST BOM_COST DEBUG
J 0
(2775 4400);
DISPLAY 1.021277 (2775 4400);
PAINT ORANGE (2775 4400);
DISPLAY INVISIBLE (2775 4400);
FORCEADD OFFPAGE..2
(-1175 4675);
FORCEPROP 2 LAST $XR0 189 
J 0
(-986 4675);
DISPLAY 0.638298 (-986 4675);
PAINT MONO (-986 4675);
FORCEPROP 1 LAST COMMENT_BODY TRUE
J 0
(-1220 4580);
DISPLAY 0.872340 (-1220 4580);
PAINT GREEN (-1220 4580);
DISPLAY INVISIBLE (-1220 4580);
FORCEPROP 2 LAST CDS_LIB mstr_standard
J 0
(-1175 4675);
PAINT ORANGE (-1175 4675);
DISPLAY INVISIBLE (-1175 4675);
FORCEPROP 2 LAST PATH I5
J 0
(-975 4725);
DISPLAY 1.021277 (-975 4725);
PAINT ORANGE (-975 4725);
DISPLAY INVISIBLE (-975 4725);
FORCEPROP 1 LAST OFFPAGE TRUE
J 0
(-850 4550);
DISPLAY 0.872340 (-850 4550);
PAINT GREEN (-850 4550);
DISPLAY INVISIBLE (-850 4550);
FORCEADD RES..2
(2325 3975);
FORCEPROP 1 LAST PACK_TYPE 0402
J 0
(2365 3800);
DISPLAY 0.617021 (2365 3800);
PAINT SKYBLUE (2365 3800);
FORCEPROP 1 LAST TOLERANCE 1%
J 0
(2370 4000);
DISPLAY 0.617021 (2370 4000);
PAINT SKYBLUE (2370 4000);
FORCEPROP 1 LAST WATTAGE 1/16W
J 0
(2365 3950);
DISPLAY 0.617021 (2365 3950);
PAINT SKYBLUE (2365 3950);
FORCEPROP 1 LAST MATERIAL CHIP
J 0
(2365 3900);
DISPLAY 0.617021 (2365 3900);
PAINT SKYBLUE (2365 3900);
FORCEPROP 1 LAST VALUE 10.0K
J 0
(2370 4050);
DISPLAY 0.617021 (2370 4050);
PAINT SKYBLUE (2370 4050);
FORCEPROP 1 LAST PART_NUMBER G21796-016
J 0
(2365 3850);
DISPLAY 0.617021 (2365 3850);
PAINT BLUE (2365 3850);
FORCEPROP 1 LAST LOCATION R8G20
J 0
(2370 4100);
DISPLAY 0.617021 (2370 4100);
PAINT AQUA (2370 4100);
FORCEPROP 1 LASTPIN (2325 3875) $PN 2
J 0
(2330 3885);
DISPLAY 0.787234 (2330 3885);
PAINT ORANGE (2330 3885);
DISPLAY INVISIBLE (2330 3885);
FORCEPROP 2 LAST CDS_LIB mstr_discrete
J 0
(2325 3975);
PAINT ORANGE (2325 3975);
DISPLAY INVISIBLE (2325 3975);
FORCEPROP 1 LASTPIN (2325 4075) $PN 1
J 0
(2330 4037);
DISPLAY 0.787234 (2330 4037);
PAINT ORANGE (2330 4037);
DISPLAY INVISIBLE (2330 4037);
FORCEPROP 2 LAST ROOM BMC_DEBUG_HEADER
J 0
(2275 4075);
DISPLAY 1.021277 (2275 4075);
PAINT ORANGE (2275 4075);
DISPLAY INVISIBLE (2275 4075);
FORCEPROP 1 LAST PATH I50
J 0
(2375 4150);
DISPLAY 0.978723 (2375 4150);
PAINT WHITE (2375 4150);
DISPLAY INVISIBLE (2375 4150);
FORCEPROP 2 LAST CDS_LOCATION R8G20
J 0
(2370 4100);
DISPLAY 0.617021 (2370 4100);
PAINT AQUA (2370 4100);
DISPLAY INVISIBLE (2370 4100);
FORCEPROP 2 LAST $SEC 1
J 0
(2375 4200);
PAINT MONO (2375 4200);
DISPLAY INVISIBLE (2375 4200);
FORCEPROP 2 LAST CDS_SEC 1
J 0
(2375 4200);
PAINT MONO (2375 4200);
DISPLAY INVISIBLE (2375 4200);
FORCEADD RES..2
(2025 3975);
FORCEPROP 1 LAST VALUE 10.0K
J 0
(2070 4050);
DISPLAY 0.617021 (2070 4050);
PAINT SKYBLUE (2070 4050);
FORCEPROP 1 LAST PACK_TYPE 0402
J 0
(2065 3800);
DISPLAY 0.617021 (2065 3800);
PAINT SKYBLUE (2065 3800);
FORCEPROP 1 LAST WATTAGE 1/16W
J 0
(2065 3950);
DISPLAY 0.617021 (2065 3950);
PAINT SKYBLUE (2065 3950);
FORCEPROP 1 LAST TOLERANCE 1%
J 0
(2070 4000);
DISPLAY 0.617021 (2070 4000);
PAINT SKYBLUE (2070 4000);
FORCEPROP 1 LAST MATERIAL CHIP
J 0
(2065 3900);
DISPLAY 0.617021 (2065 3900);
PAINT SKYBLUE (2065 3900);
FORCEPROP 1 LAST PART_NUMBER G21796-016
J 0
(2065 3850);
DISPLAY 0.617021 (2065 3850);
PAINT BLUE (2065 3850);
FORCEPROP 1 LAST LOCATION R7G23
J 0
(2070 4100);
DISPLAY 0.617021 (2070 4100);
PAINT AQUA (2070 4100);
FORCEPROP 1 LASTPIN (2025 3875) $PN 2
J 0
(2030 3885);
DISPLAY 0.787234 (2030 3885);
PAINT ORANGE (2030 3885);
DISPLAY INVISIBLE (2030 3885);
FORCEPROP 2 LAST CDS_LIB mstr_discrete
J 0
(2025 3975);
PAINT ORANGE (2025 3975);
DISPLAY INVISIBLE (2025 3975);
FORCEPROP 1 LASTPIN (2025 4075) $PN 1
J 0
(2030 4037);
DISPLAY 0.787234 (2030 4037);
PAINT ORANGE (2030 4037);
DISPLAY INVISIBLE (2030 4037);
FORCEPROP 2 LAST ROOM BMC_DEBUG_HEADER
J 0
(1975 4075);
DISPLAY 1.021277 (1975 4075);
PAINT ORANGE (1975 4075);
DISPLAY INVISIBLE (1975 4075);
FORCEPROP 1 LAST PATH I51
J 0
(2075 4150);
DISPLAY 0.978723 (2075 4150);
PAINT WHITE (2075 4150);
DISPLAY INVISIBLE (2075 4150);
FORCEPROP 2 LAST CDS_SEC 1
J 0
(2075 4200);
PAINT MONO (2075 4200);
DISPLAY INVISIBLE (2075 4200);
FORCEPROP 2 LAST CDS_LOCATION R7G23
J 0
(2070 4100);
DISPLAY 0.617021 (2070 4100);
PAINT AQUA (2070 4100);
DISPLAY INVISIBLE (2070 4100);
FORCEPROP 2 LAST $SEC 1
J 0
(2075 4200);
PAINT MONO (2075 4200);
DISPLAY INVISIBLE (2075 4200);
FORCEADD P3V3_STBY..1
(1675 4300);
FORCEPROP 3 LASTPIN (1675 4250) SIG_NAME P3V3_STBY\g
J 0
(1685 4260);
DISPLAY 0.659574 (1685 4260);
PAINT MONO (1685 4260);
DISPLAY INVISIBLE (1685 4260);
FORCEPROP 1 LAST HDL_POWER P3V3_STBY
J 0
(1375 4175);
DISPLAY 0.872340 (1375 4175);
PAINT ORANGE (1375 4175);
DISPLAY INVISIBLE (1375 4175);
FORCEPROP 1 LAST VOLTAGE 3.3V
J 0
(1630 4257);
DISPLAY 0.340426 (1630 4257);
PAINT SKYBLUE (1630 4257);
DISPLAY INVISIBLE (1630 4257);
FORCEPROP 1 LAST BODY_TYPE PLUMBING
J 0
(1630 4257);
DISPLAY 0.340426 (1630 4257);
PAINT GREEN (1630 4257);
DISPLAY INVISIBLE (1630 4257);
FORCEPROP 2 LAST CDS_LIB mstr_symbols
J 0
(1675 4300);
PAINT ORANGE (1675 4300);
DISPLAY INVISIBLE (1675 4300);
FORCEPROP 1 LAST SIZE 1B
J 0
(1720 4322);
DISPLAY 0.340426 (1720 4322);
PAINT GREEN (1720 4322);
DISPLAY INVISIBLE (1720 4322);
FORCEPROP 1 LAST PATH I52
J 0
(1720 4302);
DISPLAY 0.340426 (1720 4302);
PAINT GREEN (1720 4302);
DISPLAY INVISIBLE (1720 4302);
FORCEADD RES..2
(1675 3975);
FORCEPROP 1 LAST TOLERANCE 1%
J 0
(1720 4000);
DISPLAY 0.617021 (1720 4000);
PAINT SKYBLUE (1720 4000);
FORCEPROP 1 LAST WATTAGE 1/16W
J 0
(1715 3950);
DISPLAY 0.617021 (1715 3950);
PAINT SKYBLUE (1715 3950);
FORCEPROP 1 LAST MATERIAL CHIP
J 0
(1715 3900);
DISPLAY 0.617021 (1715 3900);
PAINT SKYBLUE (1715 3900);
FORCEPROP 1 LAST PACK_TYPE 0402
J 0
(1715 3800);
DISPLAY 0.617021 (1715 3800);
PAINT SKYBLUE (1715 3800);
FORCEPROP 1 LAST VALUE 10.0K
J 0
(1720 4050);
DISPLAY 0.617021 (1720 4050);
PAINT SKYBLUE (1720 4050);
FORCEPROP 1 LAST PART_NUMBER G21796-016
J 0
(1715 3850);
DISPLAY 0.617021 (1715 3850);
PAINT BLUE (1715 3850);
FORCEPROP 1 LAST LOCATION R7G22
J 0
(1720 4100);
DISPLAY 0.617021 (1720 4100);
PAINT AQUA (1720 4100);
FORCEPROP 1 LASTPIN (1675 4075) $PN 1
J 0
(1680 4037);
DISPLAY 0.787234 (1680 4037);
PAINT ORANGE (1680 4037);
DISPLAY INVISIBLE (1680 4037);
FORCEPROP 1 LASTPIN (1675 3875) $PN 2
J 0
(1680 3885);
DISPLAY 0.787234 (1680 3885);
PAINT ORANGE (1680 3885);
DISPLAY INVISIBLE (1680 3885);
FORCEPROP 2 LAST CDS_LIB mstr_discrete
J 0
(1675 3975);
PAINT ORANGE (1675 3975);
DISPLAY INVISIBLE (1675 3975);
FORCEPROP 2 LAST ROOM BMC_DEBUG_HEADER
J 0
(1625 4075);
DISPLAY 1.021277 (1625 4075);
PAINT ORANGE (1625 4075);
DISPLAY INVISIBLE (1625 4075);
FORCEPROP 2 LAST CDS_LOCATION R7G22
J 0
(1720 4100);
DISPLAY 0.617021 (1720 4100);
PAINT AQUA (1720 4100);
DISPLAY INVISIBLE (1720 4100);
FORCEPROP 1 LAST PATH I53
J 0
(1725 4150);
DISPLAY 0.978723 (1725 4150);
PAINT WHITE (1725 4150);
DISPLAY INVISIBLE (1725 4150);
FORCEPROP 2 LAST CDS_SEC 1
J 0
(1725 4200);
PAINT MONO (1725 4200);
DISPLAY INVISIBLE (1725 4200);
FORCEPROP 2 LAST $SEC 1
J 0
(1725 4200);
PAINT MONO (1725 4200);
DISPLAY INVISIBLE (1725 4200);
FORCEADD GND..1
(3150 3300);
FORCEPROP 3 LASTPIN (3150 3350) SIG_NAME GND\g
J 0
(3160 3360);
DISPLAY 0.659574 (3160 3360);
PAINT MONO (3160 3360);
DISPLAY INVISIBLE (3160 3360);
FORCEPROP 1 LAST BODY_TYPE PLUMBING
J 0
(3105 3257);
DISPLAY 0.340426 (3105 3257);
PAINT GREEN (3105 3257);
DISPLAY INVISIBLE (3105 3257);
FORCEPROP 1 LAST SIZE 1B
J 0
(3225 3250);
DISPLAY 0.872340 (3225 3250);
PAINT AQUA (3225 3250);
DISPLAY INVISIBLE (3225 3250);
FORCEPROP 1 LAST VOLTAGE 0.0V
J 0
(3105 3257);
DISPLAY 0.340426 (3105 3257);
PAINT SKYBLUE (3105 3257);
DISPLAY INVISIBLE (3105 3257);
FORCEPROP 1 LAST PATH I54
J 0
(3225 3300);
DISPLAY 0.872340 (3225 3300);
PAINT AQUA (3225 3300);
DISPLAY INVISIBLE (3225 3300);
FORCEPROP 2 LAST CDS_LIB mstr_symbols
J 0
(3150 3300);
PAINT ORANGE (3150 3300);
DISPLAY INVISIBLE (3150 3300);
FORCEPROP 1 LAST HDL_POWER GND
J 0
(3150 3450);
DISPLAY 0.872340 (3150 3450);
PAINT GREEN (3150 3450);
DISPLAY INVISIBLE (3150 3450);
FORCEADD GND..1
(2325 2925);
FORCEPROP 3 LASTPIN (2325 2975) SIG_NAME GND\g
J 0
(2335 2985);
DISPLAY 0.659574 (2335 2985);
PAINT MONO (2335 2985);
DISPLAY INVISIBLE (2335 2985);
FORCEPROP 1 LAST PATH I55
J 0
(2400 2925);
DISPLAY 0.872340 (2400 2925);
PAINT AQUA (2400 2925);
DISPLAY INVISIBLE (2400 2925);
FORCEPROP 1 LAST BODY_TYPE PLUMBING
J 0
(2280 2882);
DISPLAY 0.340426 (2280 2882);
PAINT GREEN (2280 2882);
DISPLAY INVISIBLE (2280 2882);
FORCEPROP 1 LAST SIZE 1B
J 0
(2400 2875);
DISPLAY 0.872340 (2400 2875);
PAINT AQUA (2400 2875);
DISPLAY INVISIBLE (2400 2875);
FORCEPROP 2 LAST CDS_LIB mstr_symbols
J 0
(2325 2925);
PAINT ORANGE (2325 2925);
DISPLAY INVISIBLE (2325 2925);
FORCEPROP 1 LAST VOLTAGE 0.0V
J 0
(2280 2882);
DISPLAY 0.340426 (2280 2882);
PAINT SKYBLUE (2280 2882);
DISPLAY INVISIBLE (2280 2882);
FORCEPROP 1 LAST HDL_POWER GND
J 0
(2325 3075);
DISPLAY 0.872340 (2325 3075);
PAINT GREEN (2325 3075);
DISPLAY INVISIBLE (2325 3075);
FORCEADD RES..2
(2325 3225);
FORCEPROP 1 LASTPIN (2325 3125) $PN 2
J 0
(2330 3135);
DISPLAY 0.617021 (2330 3135);
PAINT ORANGE (2330 3135);
FORCEPROP 1 LAST TOLERANCE 1%
J 0
(2370 3250);
DISPLAY 0.617021 (2370 3250);
PAINT SKYBLUE (2370 3250);
FORCEPROP 1 LASTPIN (2325 3325) $PN 1
J 0
(2330 3287);
DISPLAY 0.617021 (2330 3287);
PAINT ORANGE (2330 3287);
FORCEPROP 1 LAST VALUE 4.75K
J 0
(2370 3300);
DISPLAY 0.617021 (2370 3300);
PAINT SKYBLUE (2370 3300);
FORCEPROP 1 LAST WATTAGE 1/16W
J 0
(2365 3200);
DISPLAY 0.617021 (2365 3200);
PAINT SKYBLUE (2365 3200);
FORCEPROP 1 LAST MATERIAL CHIP
J 0
(2365 3150);
DISPLAY 0.617021 (2365 3150);
PAINT SKYBLUE (2365 3150);
FORCEPROP 1 LAST LOCATION R8G23
J 0
(2370 3350);
DISPLAY 0.617021 (2370 3350);
PAINT AQUA (2370 3350);
FORCEPROP 1 LAST PART_NUMBER G21796-072
J 0
(2365 3100);
DISPLAY 0.617021 (2365 3100);
PAINT BLUE (2365 3100);
FORCEPROP 1 LAST PACK_TYPE 0402
J 0
(2365 3050);
DISPLAY 0.617021 (2365 3050);
PAINT SKYBLUE (2365 3050);
FORCEPROP 2 LAST ROOM BMC_DEBUG_HEADER
J 0
(2275 3325);
DISPLAY 1.021277 (2275 3325);
PAINT ORANGE (2275 3325);
DISPLAY INVISIBLE (2275 3325);
FORCEPROP 2 LAST CDS_LIB mstr_discrete
J 0
(2325 3225);
PAINT ORANGE (2325 3225);
DISPLAY INVISIBLE (2325 3225);
FORCEPROP 2 LAST CDS_LOCATION R8G23
J 0
(2370 3350);
DISPLAY 0.617021 (2370 3350);
PAINT AQUA (2370 3350);
DISPLAY INVISIBLE (2370 3350);
FORCEPROP 1 LAST PATH I56
J 0
(2375 3400);
DISPLAY 0.978723 (2375 3400);
PAINT WHITE (2375 3400);
DISPLAY INVISIBLE (2375 3400);
FORCEPROP 2 LAST SEC 1
J 0
(2375 3450);
DISPLAY 0.680851 (2375 3450);
PAINT MONO (2375 3450);
DISPLAY INVISIBLE (2375 3450);
FORCEPROP 2 LAST SEC_TYPE 0402
J 0
(2375 3450);
DISPLAY 1.021277 (2375 3450);
PAINT ORANGE (2375 3450);
DISPLAY INVISIBLE (2375 3450);
FORCEADD OFFPAGE..5
(275 3725);
FORCEPROP 2 LAST $XR0 189 
J 0
(-10 3725);
DISPLAY 0.638298 (-10 3725);
PAINT MONO (-10 3725);
FORCEPROP 2 LAST PATH I57
J 0
(25 3775);
DISPLAY 1.021277 (25 3775);
PAINT ORANGE (25 3775);
DISPLAY INVISIBLE (25 3775);
FORCEPROP 1 LAST COMMENT_BODY TRUE
J 0
(375 3650);
DISPLAY 0.872340 (375 3650);
PAINT GREEN (375 3650);
DISPLAY INVISIBLE (375 3650);
FORCEPROP 2 LAST CDS_LIB mstr_standard
J 0
(275 3725);
PAINT ORANGE (275 3725);
DISPLAY INVISIBLE (275 3725);
FORCEPROP 1 LAST OFFPAGE TRUE
J 0
(600 3600);
DISPLAY 0.872340 (600 3600);
PAINT GREEN (600 3600);
DISPLAY INVISIBLE (600 3600);
FORCEADD OFFPAGE..1
(275 3675);
FORCEPROP 2 LAST $XR0 189 
J 0
(-7 3675);
DISPLAY 0.638298 (-7 3675);
PAINT MONO (-7 3675);
FORCEPROP 1 LAST COMMENT_BODY TRUE
J 0
(400 3575);
DISPLAY 0.872340 (400 3575);
PAINT GREEN (400 3575);
DISPLAY INVISIBLE (400 3575);
FORCEPROP 2 LAST PATH I58
J 0
(25 3725);
DISPLAY 1.021277 (25 3725);
PAINT ORANGE (25 3725);
DISPLAY INVISIBLE (25 3725);
FORCEPROP 2 LAST CDS_LIB mstr_standard
J 0
(275 3675);
PAINT ORANGE (275 3675);
DISPLAY INVISIBLE (275 3675);
FORCEPROP 1 LAST OFFPAGE TRUE
J 0
(600 3550);
DISPLAY 0.872340 (600 3550);
PAINT GREEN (600 3550);
DISPLAY INVISIBLE (600 3550);
FORCEADD OFFPAGE..1
(275 3625);
FORCEPROP 2 LAST $XR0 189 
J 0
(23 3625);
DISPLAY 0.638298 (23 3625);
PAINT MONO (23 3625);
FORCEPROP 1 LAST COMMENT_BODY TRUE
J 0
(400 3525);
DISPLAY 0.872340 (400 3525);
PAINT GREEN (400 3525);
DISPLAY INVISIBLE (400 3525);
FORCEPROP 2 LAST PATH I59
J 0
(25 3675);
DISPLAY 1.021277 (25 3675);
PAINT ORANGE (25 3675);
DISPLAY INVISIBLE (25 3675);
FORCEPROP 2 LAST CDS_LIB mstr_standard
J 0
(275 3625);
PAINT ORANGE (275 3625);
DISPLAY INVISIBLE (275 3625);
FORCEPROP 1 LAST OFFPAGE TRUE
J 0
(600 3500);
DISPLAY 0.872340 (600 3500);
PAINT GREEN (600 3500);
DISPLAY INVISIBLE (600 3500);
FORCEADD OFFPAGE..2
(-1175 4300);
FORCEPROP 2 LAST $XR0 189 
J 0
(-986 4300);
DISPLAY 0.638298 (-986 4300);
PAINT MONO (-986 4300);
FORCEPROP 1 LAST COMMENT_BODY TRUE
J 0
(-1220 4205);
DISPLAY 0.872340 (-1220 4205);
PAINT GREEN (-1220 4205);
DISPLAY INVISIBLE (-1220 4205);
FORCEPROP 2 LAST CDS_LIB mstr_standard
J 0
(-1175 4300);
PAINT ORANGE (-1175 4300);
DISPLAY INVISIBLE (-1175 4300);
FORCEPROP 2 LAST PATH I6
J 0
(-975 4350);
DISPLAY 1.021277 (-975 4350);
PAINT ORANGE (-975 4350);
DISPLAY INVISIBLE (-975 4350);
FORCEPROP 1 LAST OFFPAGE TRUE
J 0
(-850 4175);
DISPLAY 0.872340 (-850 4175);
PAINT GREEN (-850 4175);
DISPLAY INVISIBLE (-850 4175);
FORCEADD OFFPAGE..1
(275 3525);
FORCEPROP 2 LAST $XR0 189 
J 0
(23 3525);
DISPLAY 0.638298 (23 3525);
PAINT MONO (23 3525);
FORCEPROP 2 LAST CDS_LIB mstr_standard
J 0
(275 3525);
PAINT ORANGE (275 3525);
DISPLAY INVISIBLE (275 3525);
FORCEPROP 1 LAST COMMENT_BODY TRUE
J 0
(400 3425);
DISPLAY 0.872340 (400 3425);
PAINT GREEN (400 3425);
DISPLAY INVISIBLE (400 3425);
FORCEPROP 2 LAST PATH I60
J 0
(25 3575);
DISPLAY 1.021277 (25 3575);
PAINT ORANGE (25 3575);
DISPLAY INVISIBLE (25 3575);
FORCEPROP 1 LAST OFFPAGE TRUE
J 0
(600 3400);
DISPLAY 0.872340 (600 3400);
PAINT GREEN (600 3400);
DISPLAY INVISIBLE (600 3400);
FORCEADD OFFPAGE..1
(275 3575);
FORCEPROP 2 LAST $XR0 240 
J 0
(23 3575);
DISPLAY 0.638298 (23 3575);
PAINT MONO (23 3575);
FORCEPROP 2 LAST $XR1 101 
J 0
(-97 3575);
DISPLAY 0.638298 (-97 3575);
PAINT MONO (-97 3575);
FORCEPROP 2 LAST $XR2 191 
J 0
(-217 3575);
DISPLAY 0.638298 (-217 3575);
PAINT MONO (-217 3575);
FORCEPROP 2 LAST $XR3 196 
J 0
(-337 3575);
DISPLAY 0.638298 (-337 3575);
PAINT MONO (-337 3575);
FORCEPROP 2 LAST $XR4 237 
J 0
(-457 3575);
DISPLAY 0.638298 (-457 3575);
PAINT MONO (-457 3575);
FORCEPROP 2 LAST $XR5 239 
J 0
(-577 3575);
DISPLAY 0.638298 (-577 3575);
PAINT MONO (-577 3575);
FORCEPROP 1 LAST COMMENT_BODY TRUE
J 0
(400 3475);
DISPLAY 0.872340 (400 3475);
PAINT GREEN (400 3475);
DISPLAY INVISIBLE (400 3475);
FORCEPROP 2 LAST CDS_LIB mstr_standard
J 0
(275 3575);
PAINT ORANGE (275 3575);
DISPLAY INVISIBLE (275 3575);
FORCEPROP 2 LAST PATH I61
J 0
(25 3625);
DISPLAY 1.021277 (25 3625);
PAINT ORANGE (25 3625);
DISPLAY INVISIBLE (25 3625);
FORCEPROP 1 LAST OFFPAGE TRUE
J 0
(600 3450);
DISPLAY 0.872340 (600 3450);
PAINT GREEN (600 3450);
DISPLAY INVISIBLE (600 3450);
FORCEADD OFFPAGE..1
(275 3425);
FORCEPROP 2 LAST $XR0 189 
J 0
(23 3425);
DISPLAY 0.638298 (23 3425);
PAINT MONO (23 3425);
FORCEPROP 2 LAST PATH I62
J 0
(25 3475);
DISPLAY 1.021277 (25 3475);
PAINT ORANGE (25 3475);
DISPLAY INVISIBLE (25 3475);
FORCEPROP 1 LAST COMMENT_BODY TRUE
J 0
(400 3325);
DISPLAY 0.872340 (400 3325);
PAINT GREEN (400 3325);
DISPLAY INVISIBLE (400 3325);
FORCEPROP 2 LAST CDS_LIB mstr_standard
J 0
(275 3425);
PAINT ORANGE (275 3425);
DISPLAY INVISIBLE (275 3425);
FORCEPROP 1 LAST OFFPAGE TRUE
J 0
(600 3300);
DISPLAY 0.872340 (600 3300);
PAINT GREEN (600 3300);
DISPLAY INVISIBLE (600 3300);
FORCEADD RES..1
(900 3725);
FORCEPROP 1 LAST VALUE 0.0
J 2
(725 3725);
DISPLAY 0.617021 (725 3725);
PAINT SKYBLUE (725 3725);
FORCEPROP 1 LAST WATTAGE 1/16W
J 2
(850 3675);
DISPLAY 0.617021 (850 3675);
PAINT SKYBLUE (850 3675);
FORCEPROP 1 LAST TOLERANCE 5%
J 0
(750 3725);
DISPLAY 0.617021 (750 3725);
PAINT SKYBLUE (750 3725);
FORCEPROP 1 LASTPIN (800 3725) $PN 1
J 0
(812 3737);
DISPLAY 0.617021 (812 3737);
PAINT ORANGE (812 3737);
FORCEPROP 1 LAST MATERIAL CHIP
J 0
(875 3675);
DISPLAY 0.617021 (875 3675);
PAINT SKYBLUE (875 3675);
FORCEPROP 1 LAST LOCATION R7G21
J 0
(850 3775);
DISPLAY 0.617021 (850 3775);
PAINT AQUA (850 3775);
FORCEPROP 1 LASTPIN (1000 3725) $PN 2
J 0
(962 3737);
DISPLAY 0.617021 (962 3737);
PAINT ORANGE (962 3737);
FORCEPROP 1 LAST PACK_TYPE 0402
J 0
(975 3675);
DISPLAY 0.617021 (975 3675);
PAINT SKYBLUE (975 3675);
FORCEPROP 1 LAST PART_NUMBER G21497-005
J 0
(1050 3725);
DISPLAY 0.617021 (1050 3725);
PAINT BLUE (1050 3725);
FORCEPROP 2 LAST CDS_LOCATION R7G21
J 0
(850 3775);
DISPLAY 0.617021 (850 3775);
PAINT AQUA (850 3775);
DISPLAY INVISIBLE (850 3775);
FORCEPROP 2 LAST CDS_LIB mstr_discrete
J 0
(900 3725);
PAINT ORANGE (900 3725);
DISPLAY INVISIBLE (900 3725);
FORCEPROP 2 LAST ROOM BMC_DEBUG_HEADER
J 0
(850 3825);
DISPLAY 1.021277 (850 3825);
PAINT ORANGE (850 3825);
DISPLAY INVISIBLE (850 3825);
FORCEPROP 1 LAST PATH I63
J 0
(850 3875);
DISPLAY 0.978723 (850 3875);
PAINT WHITE (850 3875);
DISPLAY INVISIBLE (850 3875);
FORCEPROP 2 LAST SEC 1
J 0
(850 3925);
DISPLAY 0.680851 (850 3925);
PAINT MONO (850 3925);
DISPLAY INVISIBLE (850 3925);
FORCEPROP 2 LAST SEC_TYPE 0402
J 0
(850 3925);
DISPLAY 1.021277 (850 3925);
PAINT ORANGE (850 3925);
DISPLAY INVISIBLE (850 3925);
FORCEPROP 2 LAST BOM_COST DEBUG
J 0
(850 3875);
DISPLAY 1.021277 (850 3875);
PAINT ORANGE (850 3875);
DISPLAY INVISIBLE (850 3875);
FORCEADD RES..1
(1375 3675);
FORCEPROP 1 LAST VALUE 0.0
J 2
(1200 3675);
DISPLAY 0.617021 (1200 3675);
PAINT SKYBLUE (1200 3675);
FORCEPROP 1 LAST WATTAGE 1/16W
J 2
(1325 3625);
DISPLAY 0.617021 (1325 3625);
PAINT SKYBLUE (1325 3625);
FORCEPROP 1 LAST TOLERANCE 5%
J 0
(1225 3675);
DISPLAY 0.617021 (1225 3675);
PAINT SKYBLUE (1225 3675);
FORCEPROP 1 LASTPIN (1275 3675) $PN 1
J 0
(1287 3687);
DISPLAY 0.617021 (1287 3687);
PAINT ORANGE (1287 3687);
FORCEPROP 1 LAST MATERIAL CHIP
J 0
(1350 3625);
DISPLAY 0.617021 (1350 3625);
PAINT SKYBLUE (1350 3625);
FORCEPROP 1 LAST LOCATION R8G19
J 0
(1325 3725);
DISPLAY 0.617021 (1325 3725);
PAINT AQUA (1325 3725);
FORCEPROP 1 LASTPIN (1475 3675) $PN 2
J 0
(1437 3687);
DISPLAY 0.617021 (1437 3687);
PAINT ORANGE (1437 3687);
FORCEPROP 1 LAST PACK_TYPE 0402
J 0
(1450 3625);
DISPLAY 0.617021 (1450 3625);
PAINT SKYBLUE (1450 3625);
FORCEPROP 1 LAST PART_NUMBER G21497-005
J 0
(1525 3675);
DISPLAY 0.617021 (1525 3675);
PAINT BLUE (1525 3675);
FORCEPROP 2 LAST CDS_LIB mstr_discrete
J 0
(1375 3675);
PAINT ORANGE (1375 3675);
DISPLAY INVISIBLE (1375 3675);
FORCEPROP 2 LAST CDS_LOCATION R8G19
J 0
(1325 3725);
DISPLAY 0.617021 (1325 3725);
PAINT AQUA (1325 3725);
DISPLAY INVISIBLE (1325 3725);
FORCEPROP 2 LAST ROOM BMC_DEBUG_HEADER
J 0
(1325 3775);
DISPLAY 1.021277 (1325 3775);
PAINT ORANGE (1325 3775);
DISPLAY INVISIBLE (1325 3775);
FORCEPROP 1 LAST PATH I64
J 0
(1325 3825);
DISPLAY 0.978723 (1325 3825);
PAINT WHITE (1325 3825);
DISPLAY INVISIBLE (1325 3825);
FORCEPROP 2 LAST BOM_COST DEBUG
J 0
(1325 3825);
DISPLAY 1.021277 (1325 3825);
PAINT ORANGE (1325 3825);
DISPLAY INVISIBLE (1325 3825);
FORCEPROP 2 LAST SEC 1
J 0
(1325 3875);
DISPLAY 0.680851 (1325 3875);
PAINT MONO (1325 3875);
DISPLAY INVISIBLE (1325 3875);
FORCEPROP 2 LAST SEC_TYPE 0402
J 0
(1325 3875);
DISPLAY 1.021277 (1325 3875);
PAINT ORANGE (1325 3875);
DISPLAY INVISIBLE (1325 3875);
FORCEADD RES..1
(975 3525);
FORCEPROP 1 LAST VALUE 0.0
J 2
(800 3525);
DISPLAY 0.617021 (800 3525);
PAINT SKYBLUE (800 3525);
FORCEPROP 1 LASTPIN (875 3525) $PN 1
J 0
(887 3537);
DISPLAY 0.617021 (887 3537);
PAINT ORANGE (887 3537);
FORCEPROP 1 LAST WATTAGE 1/16W
J 2
(925 3475);
DISPLAY 0.617021 (925 3475);
PAINT SKYBLUE (925 3475);
FORCEPROP 1 LAST TOLERANCE 5%
J 0
(825 3525);
DISPLAY 0.617021 (825 3525);
PAINT SKYBLUE (825 3525);
FORCEPROP 1 LAST MATERIAL CHIP
J 0
(950 3475);
DISPLAY 0.617021 (950 3475);
PAINT SKYBLUE (950 3475);
FORCEPROP 1 LAST LOCATION R8G21
J 0
(925 3575);
DISPLAY 0.617021 (925 3575);
PAINT AQUA (925 3575);
FORCEPROP 1 LASTPIN (1075 3525) $PN 2
J 0
(1037 3537);
DISPLAY 0.617021 (1037 3537);
PAINT ORANGE (1037 3537);
FORCEPROP 1 LAST PACK_TYPE 0402
J 0
(1050 3475);
DISPLAY 0.617021 (1050 3475);
PAINT SKYBLUE (1050 3475);
FORCEPROP 1 LAST PART_NUMBER G21497-005
J 0
(1125 3525);
DISPLAY 0.617021 (1125 3525);
PAINT BLUE (1125 3525);
FORCEPROP 2 LAST CDS_LIB mstr_discrete
J 0
(975 3525);
PAINT ORANGE (975 3525);
DISPLAY INVISIBLE (975 3525);
FORCEPROP 2 LAST CDS_LOCATION R8G21
J 0
(925 3575);
DISPLAY 0.617021 (925 3575);
PAINT AQUA (925 3575);
DISPLAY INVISIBLE (925 3575);
FORCEPROP 2 LAST BOM_COST DEBUG
J 0
(925 3675);
DISPLAY 1.021277 (925 3675);
PAINT ORANGE (925 3675);
DISPLAY INVISIBLE (925 3675);
FORCEPROP 2 LAST SEC_TYPE 0402
J 0
(925 3725);
DISPLAY 1.021277 (925 3725);
PAINT ORANGE (925 3725);
DISPLAY INVISIBLE (925 3725);
FORCEPROP 2 LAST SEC 1
J 0
(925 3725);
DISPLAY 0.680851 (925 3725);
PAINT MONO (925 3725);
DISPLAY INVISIBLE (925 3725);
FORCEPROP 1 LAST PATH I65
J 0
(925 3675);
DISPLAY 0.978723 (925 3675);
PAINT WHITE (925 3675);
DISPLAY INVISIBLE (925 3675);
FORCEPROP 2 LAST ROOM BMC_DEBUG_HEADER
J 0
(925 3625);
DISPLAY 1.021277 (925 3625);
PAINT ORANGE (925 3625);
DISPLAY INVISIBLE (925 3625);
FORCEADD RES..1
(1600 3425);
FORCEPROP 1 LAST VALUE 0.0
J 2
(1425 3425);
DISPLAY 0.617021 (1425 3425);
PAINT SKYBLUE (1425 3425);
FORCEPROP 1 LAST TOLERANCE 5%
J 0
(1450 3425);
DISPLAY 0.617021 (1450 3425);
PAINT SKYBLUE (1450 3425);
FORCEPROP 1 LASTPIN (1500 3425) $PN 1
J 0
(1512 3437);
DISPLAY 0.617021 (1512 3437);
PAINT ORANGE (1512 3437);
FORCEPROP 1 LAST WATTAGE 1/16W
J 2
(1550 3375);
DISPLAY 0.617021 (1550 3375);
PAINT SKYBLUE (1550 3375);
FORCEPROP 1 LASTPIN (1700 3425) $PN 2
J 0
(1662 3437);
DISPLAY 0.617021 (1662 3437);
PAINT ORANGE (1662 3437);
FORCEPROP 1 LAST MATERIAL CHIP
J 0
(1575 3375);
DISPLAY 0.617021 (1575 3375);
PAINT SKYBLUE (1575 3375);
FORCEPROP 1 LAST PART_NUMBER G21497-005
J 0
(1750 3425);
DISPLAY 0.617021 (1750 3425);
PAINT BLUE (1750 3425);
FORCEPROP 1 LAST LOCATION R8G22
J 0
(1550 3475);
DISPLAY 0.617021 (1550 3475);
PAINT AQUA (1550 3475);
FORCEPROP 1 LAST PACK_TYPE 0402
J 0
(1675 3375);
DISPLAY 0.617021 (1675 3375);
PAINT SKYBLUE (1675 3375);
FORCEPROP 2 LAST CDS_LIB mstr_discrete
J 0
(1600 3425);
PAINT ORANGE (1600 3425);
DISPLAY INVISIBLE (1600 3425);
FORCEPROP 2 LAST CDS_LOCATION R8G22
J 0
(1550 3475);
DISPLAY 0.617021 (1550 3475);
PAINT AQUA (1550 3475);
DISPLAY INVISIBLE (1550 3475);
FORCEPROP 2 LAST ROOM BMC_DEBUG_HEADER
J 0
(1550 3525);
DISPLAY 1.021277 (1550 3525);
PAINT ORANGE (1550 3525);
DISPLAY INVISIBLE (1550 3525);
FORCEPROP 1 LAST PATH I66
J 0
(1550 3575);
DISPLAY 0.978723 (1550 3575);
PAINT WHITE (1550 3575);
DISPLAY INVISIBLE (1550 3575);
FORCEPROP 2 LAST BOM_COST DEBUG
J 0
(1550 3575);
DISPLAY 1.021277 (1550 3575);
PAINT ORANGE (1550 3575);
DISPLAY INVISIBLE (1550 3575);
FORCEPROP 2 LAST SEC_TYPE 0402
J 0
(1550 3625);
DISPLAY 1.021277 (1550 3625);
PAINT ORANGE (1550 3625);
DISPLAY INVISIBLE (1550 3625);
FORCEPROP 2 LAST SEC 1
J 0
(1550 3625);
DISPLAY 0.680851 (1550 3625);
PAINT MONO (1550 3625);
DISPLAY INVISIBLE (1550 3625);
FORCEADD RES..1
(-1900 4675);
FORCEPROP 1 LAST VALUE 0.0
J 2
(-2075 4675);
DISPLAY 0.617021 (-2075 4675);
PAINT SKYBLUE (-2075 4675);
FORCEPROP 1 LAST WATTAGE 1/16W
J 2
(-1975 4625);
DISPLAY 0.617021 (-1975 4625);
PAINT SKYBLUE (-1975 4625);
FORCEPROP 1 LAST TOLERANCE 5%
J 0
(-2050 4675);
DISPLAY 0.617021 (-2050 4675);
PAINT SKYBLUE (-2050 4675);
FORCEPROP 1 LASTPIN (-2000 4675) $PN 1
J 0
(-1988 4687);
DISPLAY 0.617021 (-1988 4687);
PAINT ORANGE (-1988 4687);
FORCEPROP 1 LAST MATERIAL CHIP
J 0
(-1950 4625);
DISPLAY 0.617021 (-1950 4625);
PAINT SKYBLUE (-1950 4625);
FORCEPROP 1 LAST LOCATION R8G10
J 0
(-1950 4725);
DISPLAY 0.617021 (-1950 4725);
PAINT AQUA (-1950 4725);
FORCEPROP 1 LASTPIN (-1800 4675) $PN 2
J 0
(-1838 4687);
DISPLAY 0.617021 (-1838 4687);
PAINT ORANGE (-1838 4687);
FORCEPROP 1 LAST PACK_TYPE 0402
J 0
(-1825 4625);
DISPLAY 0.617021 (-1825 4625);
PAINT SKYBLUE (-1825 4625);
FORCEPROP 1 LAST PART_NUMBER G21497-005
J 0
(-1750 4675);
DISPLAY 0.617021 (-1750 4675);
PAINT BLUE (-1750 4675);
FORCEPROP 2 LAST ROOM BMC_DEBUG_HEADER
J 0
(-1950 4775);
DISPLAY 1.021277 (-1950 4775);
PAINT ORANGE (-1950 4775);
DISPLAY INVISIBLE (-1950 4775);
FORCEPROP 2 LAST CDS_LOCATION R8G10
J 0
(-1950 4725);
DISPLAY 0.617021 (-1950 4725);
PAINT AQUA (-1950 4725);
DISPLAY INVISIBLE (-1950 4725);
FORCEPROP 2 LAST CDS_LIB mstr_discrete
J 0
(-1900 4675);
PAINT ORANGE (-1900 4675);
DISPLAY INVISIBLE (-1900 4675);
FORCEPROP 1 LAST PATH I7
J 0
(-1950 4825);
DISPLAY 0.978723 (-1950 4825);
PAINT WHITE (-1950 4825);
DISPLAY INVISIBLE (-1950 4825);
FORCEPROP 2 LAST BOM_COST DEBUG
J 0
(-1950 4825);
DISPLAY 1.021277 (-1950 4825);
PAINT ORANGE (-1950 4825);
DISPLAY INVISIBLE (-1950 4825);
FORCEPROP 2 LAST SEC 1
J 0
(-1950 4875);
DISPLAY 0.680851 (-1950 4875);
PAINT MONO (-1950 4875);
DISPLAY INVISIBLE (-1950 4875);
FORCEPROP 2 LAST SEC_TYPE 0402
J 0
(-1950 4875);
DISPLAY 1.021277 (-1950 4875);
PAINT ORANGE (-1950 4875);
DISPLAY INVISIBLE (-1950 4875);
FORCEADD RES..1
(-1900 4300);
FORCEPROP 1 LAST VALUE 0.0
J 2
(-2075 4300);
DISPLAY 0.617021 (-2075 4300);
PAINT SKYBLUE (-2075 4300);
FORCEPROP 1 LAST WATTAGE 1/16W
J 2
(-1975 4250);
DISPLAY 0.617021 (-1975 4250);
PAINT SKYBLUE (-1975 4250);
FORCEPROP 1 LAST TOLERANCE 5%
J 0
(-2050 4300);
DISPLAY 0.617021 (-2050 4300);
PAINT SKYBLUE (-2050 4300);
FORCEPROP 1 LASTPIN (-2000 4300) $PN 1
J 0
(-1988 4312);
DISPLAY 0.617021 (-1988 4312);
PAINT ORANGE (-1988 4312);
FORCEPROP 1 LAST MATERIAL EMPTY
J 0
(-1950 4250);
DISPLAY 0.617021 (-1950 4250);
PAINT RED (-1950 4250);
FORCEPROP 1 LASTPIN (-1800 4300) $PN 2
J 0
(-1838 4312);
DISPLAY 0.617021 (-1838 4312);
PAINT ORANGE (-1838 4312);
FORCEPROP 1 LAST LOCATION R7G19
J 0
(-1950 4350);
DISPLAY 0.617021 (-1950 4350);
PAINT AQUA (-1950 4350);
FORCEPROP 1 LAST PACK_TYPE 0402
J 0
(-1800 4250);
DISPLAY 0.617021 (-1800 4250);
PAINT SKYBLUE (-1800 4250);
FORCEPROP 1 LAST PART_NUMBER G21497-005
J 0
(-1750 4300);
DISPLAY 0.617021 (-1750 4300);
PAINT BLUE (-1750 4300);
FORCEPROP 2 LAST CDS_LIB mstr_discrete
J 0
(-1900 4300);
PAINT ORANGE (-1900 4300);
DISPLAY INVISIBLE (-1900 4300);
FORCEPROP 2 LAST CDS_LOCATION R7G19
J 0
(-1950 4350);
DISPLAY 0.617021 (-1950 4350);
PAINT AQUA (-1950 4350);
DISPLAY INVISIBLE (-1950 4350);
FORCEPROP 2 LAST ROOM BMC_DEBUG_HEADER
J 0
(-1950 4400);
DISPLAY 1.021277 (-1950 4400);
PAINT ORANGE (-1950 4400);
DISPLAY INVISIBLE (-1950 4400);
FORCEPROP 1 LAST PATH I8
J 0
(-1950 4450);
DISPLAY 0.978723 (-1950 4450);
PAINT WHITE (-1950 4450);
DISPLAY INVISIBLE (-1950 4450);
FORCEPROP 2 LAST BOM_COST DEBUG
J 0
(-1950 4450);
DISPLAY 1.021277 (-1950 4450);
PAINT ORANGE (-1950 4450);
DISPLAY INVISIBLE (-1950 4450);
FORCEPROP 2 LAST SEC 1
J 0
(-1950 4500);
DISPLAY 0.680851 (-1950 4500);
PAINT MONO (-1950 4500);
DISPLAY INVISIBLE (-1950 4500);
FORCEPROP 2 LAST SEC_TYPE 0402
J 0
(-1950 4500);
DISPLAY 1.021277 (-1950 4500);
PAINT ORANGE (-1950 4500);
DISPLAY INVISIBLE (-1950 4500);
FORCEADD RES..1
(-1900 4500);
FORCEPROP 1 LAST VALUE 0.0
J 2
(-2075 4500);
DISPLAY 0.617021 (-2075 4500);
PAINT SKYBLUE (-2075 4500);
FORCEPROP 1 LAST WATTAGE 1/16W
J 2
(-1975 4450);
DISPLAY 0.617021 (-1975 4450);
PAINT SKYBLUE (-1975 4450);
FORCEPROP 1 LAST TOLERANCE 5%
J 0
(-2050 4500);
DISPLAY 0.617021 (-2050 4500);
PAINT SKYBLUE (-2050 4500);
FORCEPROP 1 LASTPIN (-2000 4500) $PN 1
J 0
(-1988 4512);
DISPLAY 0.617021 (-1988 4512);
PAINT ORANGE (-1988 4512);
FORCEPROP 1 LAST LOCATION R8G9
J 0
(-1950 4550);
DISPLAY 0.617021 (-1950 4550);
PAINT AQUA (-1950 4550);
FORCEPROP 1 LAST MATERIAL EMPTY
J 0
(-1950 4450);
DISPLAY 0.617021 (-1950 4450);
PAINT RED (-1950 4450);
FORCEPROP 1 LASTPIN (-1800 4500) $PN 2
J 0
(-1838 4512);
DISPLAY 0.617021 (-1838 4512);
PAINT ORANGE (-1838 4512);
FORCEPROP 1 LAST PACK_TYPE 0402
J 0
(-1800 4450);
DISPLAY 0.617021 (-1800 4450);
PAINT SKYBLUE (-1800 4450);
FORCEPROP 1 LAST PART_NUMBER G21497-005
J 0
(-1750 4500);
DISPLAY 0.617021 (-1750 4500);
PAINT BLUE (-1750 4500);
FORCEPROP 2 LAST CDS_LOCATION R8G9
J 0
(-1950 4550);
DISPLAY 0.617021 (-1950 4550);
PAINT AQUA (-1950 4550);
DISPLAY INVISIBLE (-1950 4550);
FORCEPROP 2 LAST CDS_LIB mstr_discrete
J 0
(-1900 4500);
PAINT MONO (-1900 4500);
DISPLAY INVISIBLE (-1900 4500);
FORCEPROP 2 LAST ROOM BMC_DEBUG_HEADER
J 0
(-1950 4600);
DISPLAY 1.021277 (-1950 4600);
PAINT ORANGE (-1950 4600);
DISPLAY INVISIBLE (-1950 4600);
FORCEPROP 2 LAST BOM_COST DEBUG
J 0
(-1950 4650);
DISPLAY 1.021277 (-1950 4650);
PAINT ORANGE (-1950 4650);
DISPLAY INVISIBLE (-1950 4650);
FORCEPROP 2 LAST CDS_SEC 1
J 0
(-1950 4700);
PAINT MONO (-1950 4700);
DISPLAY INVISIBLE (-1950 4700);
FORCEPROP 2 LAST $SEC 1
J 0
(-1950 4700);
PAINT MONO (-1950 4700);
DISPLAY INVISIBLE (-1950 4700);
FORCEPROP 1 LAST PATH I9
J 0
(-1950 4650);
DISPLAY 0.978723 (-1950 4650);
PAINT WHITE (-1950 4650);
DISPLAY INVISIBLE (-1950 4650);
FORCEADD DESIGN_NOTE..1
(-275 1125);
FORCEPROP 0 LAST L2 CPLD JTAG DISABLED WHEN LOW
J 0
(-475 925);
DISPLAY 1.063830 (-475 925);
PAINT WHITE (-475 925);
FORCEPROP 0 LAST L3 CPLD JTAG ENABLED WHEN HIGH (DEFAULT)
J 0
(-475 1000);
DISPLAY 1.085106 (-475 1000);
PAINT ORANGE (-475 1000);
FORCEPROP 2 LAST ROOM SB
J 0
(-450 1025);
DISPLAY 1.361702 (-450 1025);
PAINT ORANGE (-450 1025);
DISPLAY INVISIBLE (-450 1025);
FORCEPROP 2 LAST CDS_LIB mstr_symbols
J 0
(-275 1125);
PAINT ORANGE (-275 1125);
DISPLAY INVISIBLE (-275 1125);
FORCEPROP 2 LAST BOM_COST SB
J 0
(-450 1025);
DISPLAY 1.361702 (-450 1025);
PAINT ORANGE (-450 1025);
DISPLAY INVISIBLE (-450 1025);
FORCEPROP 1 LAST COMMENT_BODY TRUE
J 0
(-250 1225);
DISPLAY 1.319149 (-250 1225);
PAINT ORANGE (-250 1225);
DISPLAY INVISIBLE (-250 1225);
FORCEADD DNS..2
(-1895 4295);
PAINT RED (-1895 4295);
FORCEPROP 1 LAST COMMENT_BODY TRUE
R 1
J 0
(-1820 4070);
DISPLAY 0.872340 (-1820 4070);
PAINT GREEN (-1820 4070);
DISPLAY INVISIBLE (-1820 4070);
FORCEPROP 2 LAST CDS_LIB mstr_misc
J 0
(-1895 4295);
PAINT ORANGE (-1895 4295);
DISPLAY INVISIBLE (-1895 4295);
FORCEADD BOM_NOTE..1
(-3075 1325);
FORCEPROP 0 LAST L1 UNSTUFF CPLD AND BMC RES FOR PCH OR PCH GBE
J 0
(-3200 1200);
DISPLAY 1.021277 (-3200 1200);
PAINT ORANGE (-3200 1200);
FORCEPROP 2 LAST CDS_LIB mstr_symbols
J 0
(-3075 1325);
PAINT ORANGE (-3075 1325);
DISPLAY INVISIBLE (-3075 1325);
FORCEPROP 1 LAST COMMENT_BODY TRUE
J 0
(-3050 1425);
DISPLAY 0.978723 (-3050 1425);
PAINT ORANGE (-3050 1425);
DISPLAY INVISIBLE (-3050 1425);
FORCEADD DNS..2
(-1895 4495);
PAINT RED (-1895 4495);
FORCEPROP 1 LAST COMMENT_BODY TRUE
R 1
J 0
(-1820 4270);
DISPLAY 0.872340 (-1820 4270);
PAINT GREEN (-1820 4270);
DISPLAY INVISIBLE (-1820 4270);
FORCEPROP 2 LAST CDS_LIB mstr_misc
J 0
(-1895 4495);
PAINT ORANGE (-1895 4495);
DISPLAY INVISIBLE (-1895 4495);
FORCEADD DESIGN_NOTE..1
(2275 4800);
FORCEPROP 0 LAST L1 1N5819HW USED TO PREVENT LEAKAGE ONTO P3V3_STBY RAIL
J 0
(2075 4675);
DISPLAY 0.808511 (2075 4675);
PAINT ORANGE (2075 4675);
FORCEPROP 0 LAST L2 FROM JTAG DEBUG DEVICES PLUGGED INTO THE BOARD
J 0
(2075 4625);
DISPLAY 0.808511 (2075 4625);
PAINT ORANGE (2075 4625);
FORCEPROP 2 LAST CDS_LIB mstr_symbols
J 0
(2275 4800);
PAINT MONO (2275 4800);
DISPLAY INVISIBLE (2275 4800);
FORCEPROP 1 LAST COMMENT_BODY TRUE
J 0
(2300 4900);
DISPLAY 0.978723 (2300 4900);
PAINT ORANGE (2300 4900);
DISPLAY INVISIBLE (2300 4900);
FORCEADD BOM_NOTE..1
(700 3225);
FORCEPROP 0 LAST L1 UNSTUFF 0-OHM RESISTORS FOR
J 0
(575 3100);
DISPLAY 1.021277 (575 3100);
PAINT ORANGE (575 3100);
FORCEPROP 0 LAST L2 BMC TO CPLD COMMUNICATION
J 0
(575 3050);
DISPLAY 1.021277 (575 3050);
PAINT ORANGE (575 3050);
FORCEPROP 1 LAST COMMENT_BODY TRUE
J 0
(725 3325);
DISPLAY 0.978723 (725 3325);
PAINT ORANGE (725 3325);
DISPLAY INVISIBLE (725 3325);
FORCEPROP 2 LAST CDS_LIB mstr_symbols
J 0
(700 3225);
PAINT ORANGE (700 3225);
DISPLAY INVISIBLE (700 3225);
FORCEADD DNS..2
(-1895 2870);
PAINT RED (-1895 2870);
FORCEPROP 1 LAST COMMENT_BODY TRUE
R 1
J 0
(-1820 2645);
DISPLAY 0.872340 (-1820 2645);
PAINT GREEN (-1820 2645);
DISPLAY INVISIBLE (-1820 2645);
FORCEPROP 2 LAST CDS_LIB mstr_misc
J 0
(-1895 2870);
PAINT ORANGE (-1895 2870);
DISPLAY INVISIBLE (-1895 2870);
FORCEADD DNS..2
(-1895 1970);
PAINT RED (-1895 1970);
FORCEPROP 1 LAST COMMENT_BODY TRUE
R 1
J 0
(-1820 1745);
DISPLAY 0.872340 (-1820 1745);
PAINT GREEN (-1820 1745);
DISPLAY INVISIBLE (-1820 1745);
FORCEPROP 2 LAST CDS_LIB mstr_misc
J 0
(-1895 1970);
PAINT ORANGE (-1895 1970);
DISPLAY INVISIBLE (-1895 1970);
FORCEADD DNS..2
(-1895 4120);
PAINT RED (-1895 4120);
FORCEPROP 1 LAST COMMENT_BODY TRUE
R 1
J 0
(-1820 3895);
DISPLAY 0.872340 (-1820 3895);
PAINT GREEN (-1820 3895);
DISPLAY INVISIBLE (-1820 3895);
FORCEPROP 2 LAST CDS_LIB mstr_misc
J 0
(-1895 4120);
PAINT ORANGE (-1895 4120);
DISPLAY INVISIBLE (-1895 4120);
FORCEADD DNS..2
(-170 1520);
PAINT RED (-170 1520);
FORCEPROP 1 LAST COMMENT_BODY TRUE
R 1
J 0
(-95 1295);
DISPLAY 0.872340 (-95 1295);
PAINT GREEN (-95 1295);
DISPLAY INVISIBLE (-95 1295);
FORCEPROP 2 LAST CDS_LIB mstr_misc
J 0
(-170 1520);
PAINT ORANGE (-170 1520);
DISPLAY INVISIBLE (-170 1520);
FORCEADD DNS..2
(-1895 2145);
PAINT RED (-1895 2145);
FORCEPROP 1 LAST COMMENT_BODY TRUE
R 1
J 0
(-1820 1920);
DISPLAY 0.872340 (-1820 1920);
PAINT GREEN (-1820 1920);
DISPLAY INVISIBLE (-1820 1920);
FORCEPROP 2 LAST CDS_LIB mstr_misc
J 0
(-1895 2145);
PAINT ORANGE (-1895 2145);
DISPLAY INVISIBLE (-1895 2145);
FORCEADD DNS..2
(-1895 2695);
PAINT RED (-1895 2695);
FORCEPROP 1 LAST COMMENT_BODY TRUE
R 1
J 0
(-1820 2470);
DISPLAY 0.872340 (-1820 2470);
PAINT GREEN (-1820 2470);
DISPLAY INVISIBLE (-1820 2470);
FORCEPROP 2 LAST CDS_LIB mstr_misc
J 0
(-1895 2695);
PAINT ORANGE (-1895 2695);
DISPLAY INVISIBLE (-1895 2695);
FORCEADD DNS..2
(-1895 3570);
PAINT RED (-1895 3570);
FORCEPROP 1 LAST COMMENT_BODY TRUE
R 1
J 0
(-1820 3345);
DISPLAY 0.872340 (-1820 3345);
PAINT GREEN (-1820 3345);
DISPLAY INVISIBLE (-1820 3345);
FORCEPROP 2 LAST CDS_LIB mstr_misc
J 0
(-1895 3570);
PAINT ORANGE (-1895 3570);
DISPLAY INVISIBLE (-1895 3570);
FORCEADD DNS..2
(-1895 3395);
PAINT RED (-1895 3395);
FORCEPROP 1 LAST COMMENT_BODY TRUE
R 1
J 0
(-1820 3170);
DISPLAY 0.872340 (-1820 3170);
PAINT GREEN (-1820 3170);
DISPLAY INVISIBLE (-1820 3170);
FORCEPROP 2 LAST CDS_LIB mstr_misc
J 0
(-1895 3395);
PAINT ORANGE (-1895 3395);
DISPLAY INVISIBLE (-1895 3395);
FORCEADD INTEL_CORP_BPAGE..1
(4250 75);
FORCEPROP 1 LAST CDS_CON_LAST_MODIFIED Tue Dec 01 11:52:17 2015
J 0
(2825 400);
PAINT ORANGE (2825 400);
DISPLAY INVISIBLE (2825 400);
FORCEPROP 1 LAST CUSTOM_TXT_CDS <CURRENT_DESIGN_SHEET> OF <TOTAL_DESIGN_SHEETS>
J 0
(3750 100);
PAINT GREEN (3750 100);
FORCEPROP 1 LAST CUSTOM_TXT_CDS <CON_LAST_MODIFIED>
J 0
(2325 425);
PAINT GREEN (2325 425);
FORCEPROP 2 LAST CUSTOM_TXT_CDS <XR_PAGE_TITLE>
J 0
(-3640 5325);
DISPLAY 0.638298 (-3640 5325);
PAINT PINK (-3640 5325);
DISPLAY INVISIBLE (-3640 5325);
FORCEPROP 1 LAST SCH_TITLE BMC JTAG HEADER
J 0
(-3700 125);
DISPLAY 1.212766 (-3700 125);
PAINT ORANGE (-3700 125);
FORCEPROP 1 LAST SCH_REV 2.420
J 0
(4000 225);
DISPLAY 0.978723 (4000 225);
PAINT YELLOW (4000 225);
FORCEPROP 1 LAST SCH_DEPT BESD
J 1
(-200 175);
DISPLAY 1.212766 (-200 175);
PAINT YELLOW (-200 175);
FORCEPROP 1 LAST SCH_NUMBER H4694802
J 0
(2950 225);
DISPLAY 1.212766 (2950 225);
PAINT YELLOW (2950 225);
FORCEPROP 1 LAST SCH_ADDRESS2 P.O. BOX 58119
J 0
(275 150);
DISPLAY 0.617021 (275 150);
PAINT GREEN (275 150);
FORCEPROP 1 LAST SCH_ADDRESS1 2200 Mission College Blvd.
J 0
(275 200);
DISPLAY 0.617021 (275 200);
PAINT GREEN (275 200);
FORCEPROP 1 LAST SCH_ADDRESS3 Santa Clara, CA 95052-8119
J 0
(275 100);
DISPLAY 0.617021 (275 100);
PAINT GREEN (275 100);
FORCEPROP 2 LAST PAGE_BORDER TRUE
J 0
(-3640 5325);
DISPLAY 0.638298 (-3640 5325);
PAINT PINK (-3640 5325);
DISPLAY INVISIBLE (-3640 5325);
FORCEPROP 1 LAST COMMENT_BODY TRUE
J 0
(4262 87);
DISPLAY 0.468085 (4262 87);
PAINT GREEN (4262 87);
DISPLAY INVISIBLE (4262 87);
FORCEPROP 2 LAST CDS_LIB mstr_symbols
J 0
(4250 75);
PAINT MONO (4250 75);
DISPLAY INVISIBLE (4250 75);
FORCEPROP 2 LAST CDS_XR_PAGE_TITLE CR-189 : @BASEBOARD_FAB2_LIB.BASEBOARD_FAB2(SCH_1):PAGE189
J 0
(-3640 5325);
DISPLAY 0.638298 (-3640 5325);
PAINT PINK (-3640 5325);
DISPLAY INVISIBLE (-3640 5325);
WIRE 16 -1 (-175 2075)(-175 2025);
WIRE 16 -1 (-175 1425)(-175 1375);
WIRE 16 -1 (2650 4300)(2650 4050);
WIRE 16 -1 (2650 4050)(2700 4050);
WIRE 16 -1 (2025 4150)(2325 4150);
WIRE 16 -1 (2025 4075)(2025 4150);
WIRE 16 -1 (1675 4150)(2025 4150);
WIRE 16 -1 (2325 4150)(2325 4075);
WIRE 16 -1 (1675 4075)(1675 4150);
WIRE 16 -1 (1675 4150)(1675 4250);
WIRE 16 -1 (3275 3475)(3150 3475);
WIRE 16 -1 (3150 3475)(3150 3350);
WIRE 16 -1 (2325 3125)(2325 2975);
WIRE 16 -1 (1075 3525)(2325 3525);
WIRE 16 -1 (2325 3525)(3275 3525);
FORCEPROP 2 LAST SIG_NAME JTAG_TMS_R
J 0
(2390 3535);
DISPLAY 0.617021 (2390 3535);
PAINT ORANGE (2390 3535);
FORCEPROP 2 LASTPROP $XRERR UNIQUE?
J 0
(2150 3535);
DISPLAY 0.638298 (2150 3535);
PAINT MONO (2150 3535);
DISPLAY INVISIBLE (2150 3535);
WIRE 16 -1 (2325 3875)(2325 3525);
WIRE 16 -1 (3275 3575)(325 3575);
FORCEPROP 2 LAST SIG_NAME PWRGD_P3V3_STBY
J 0
(340 3585);
DISPLAY 0.617021 (340 3585);
PAINT ORANGE (340 3585);
WIRE 16 -1 (3275 3625)(325 3625);
FORCEPROP 2 LAST SIG_NAME JTAG_TRST_N
J 0
(340 3635);
DISPLAY 0.617021 (340 3635);
PAINT ORANGE (340 3635);
WIRE 16 -1 (325 3675)(1275 3675);
FORCEPROP 2 LAST SIG_NAME JTAG_TDI
J 0
(340 3685);
DISPLAY 0.617021 (340 3685);
PAINT ORANGE (340 3685);
WIRE 16 -1 (-175 1725)(625 1725);
WIRE 16 -1 (-175 1825)(-175 1725);
WIRE 16 -1 (-175 1725)(-175 1625);
WIRE 16 682 (-850 4850)(-3500 4850);
WIRE 16 682 (-850 1175)(-850 4850);
WIRE 16 682 (-3500 4850)(-3500 1175);
WIRE 16 682 (-3500 1175)(-850 1175);
WIRE 16 -1 (325 3425)(1500 3425);
FORCEPROP 2 LAST SIG_NAME JTAG_TCK
J 0
(340 3435);
DISPLAY 0.617021 (340 3435);
PAINT ORANGE (340 3435);
WIRE 16 -1 (3125 3775)(3125 4050);
FORCEPROP 0 LAST VOLTAGE 3.3
J 0
(3125 3950);
DISPLAY 1.021277 (3125 3950);
PAINT SKYBLUE (3125 3950);
DISPLAY INVISIBLE (3125 3950);
WIRE 16 -1 (3275 3775)(3125 3775);
FORCEPROP 2 LAST SIG_NAME P3V3_STBY_PLD_D
J 0
(2915 4085);
DISPLAY 0.617021 (2915 4085);
PAINT ORANGE (2915 4085);
FORCEPROP 2 LASTPROP $XRERR UNIQUE?
J 0
(2675 4085);
DISPLAY 0.638298 (2675 4085);
PAINT MONO (2675 4085);
DISPLAY INVISIBLE (2675 4085);
WIRE 16 -1 (3125 4050)(2900 4050);
WIRE 16 -1 (2325 3325)(2325 3425);
WIRE 16 -1 (3275 3425)(2325 3425);
FORCEPROP 2 LAST SIG_NAME JTAG_TCK_R
J 0
(2390 3435);
DISPLAY 0.617021 (2390 3435);
PAINT ORANGE (2390 3435);
FORCEPROP 2 LASTPROP $XRERR UNIQUE?
J 0
(2150 3435);
DISPLAY 0.638298 (2150 3435);
PAINT MONO (2150 3435);
DISPLAY INVISIBLE (2150 3435);
WIRE 16 -1 (1700 3425)(2325 3425);
WIRE 16 -1 (1675 3875)(1675 3725);
WIRE 16 -1 (3275 3725)(1675 3725);
FORCEPROP 2 LAST SIG_NAME JTAG_TDO_R
J 0
(2390 3735);
DISPLAY 0.617021 (2390 3735);
PAINT ORANGE (2390 3735);
FORCEPROP 2 LASTPROP $XRERR UNIQUE?
J 0
(2150 3735);
DISPLAY 0.638298 (2150 3735);
PAINT MONO (2150 3735);
DISPLAY INVISIBLE (2150 3735);
WIRE 16 -1 (1000 3725)(1675 3725);
WIRE 16 -1 (2025 3875)(2025 3675);
WIRE 16 -1 (3275 3675)(2025 3675);
FORCEPROP 2 LAST SIG_NAME JTAG_TDI_R
J 0
(2390 3685);
DISPLAY 0.617021 (2390 3685);
PAINT ORANGE (2390 3685);
FORCEPROP 2 LASTPROP $XRERR UNIQUE?
J 0
(2150 3685);
DISPLAY 0.638298 (2150 3685);
PAINT MONO (2150 3685);
DISPLAY INVISIBLE (2150 3685);
WIRE 16 -1 (1475 3675)(2025 3675);
WIRE 16 -1 (325 3725)(800 3725);
FORCEPROP 2 LAST SIG_NAME JTAG_TDO
J 0
(340 3735);
DISPLAY 0.617021 (340 3735);
PAINT ORANGE (340 3735);
WIRE 16 -1 (325 3525)(875 3525);
FORCEPROP 2 LAST SIG_NAME JTAG_TMS
J 0
(340 3535);
DISPLAY 0.617021 (340 3535);
PAINT ORANGE (340 3535);
WIRE 16 -1 (-1475 4675)(-1225 4675);
FORCEPROP 0 LAST SIG_NAME JTAG_TRST_N
J 1
(-1325 4685);
DISPLAY 0.617021 (-1325 4685);
PAINT ORANGE (-1325 4685);
WIRE 16 -1 (-1475 4500)(-1475 4675);
WIRE 16 -1 (-1800 4675)(-1475 4675);
WIRE 16 -1 (-1800 4500)(-1475 4500);
WIRE 16 -1 (-1475 4300)(-1225 4300);
FORCEPROP 0 LAST SIG_NAME JTAG_TDI
J 1
(-1325 4310);
DISPLAY 0.617021 (-1325 4310);
PAINT ORANGE (-1325 4310);
WIRE 16 -1 (-1475 4300)(-1475 4125);
WIRE 16 -1 (-1800 4300)(-1475 4300);
WIRE 16 -1 (-1800 4125)(-1475 4125);
WIRE 16 -1 (-1475 4125)(-1475 3950);
WIRE 16 -1 (-1475 3775)(-1475 3950);
WIRE 16 -1 (-1800 3950)(-1475 3950);
WIRE 16 -1 (-1800 3775)(-1475 3775);
WIRE 16 -1 (-2000 4675)(-2600 4675);
FORCEPROP 2 LAST SIG_NAME JTAG_BMC_TRST_N
J 0
(-2585 4685);
DISPLAY 0.617021 (-2585 4685);
PAINT ORANGE (-2585 4685);
WIRE 16 -1 (-2000 4500)(-2600 4500);
FORCEPROP 2 LAST SIG_NAME JTAG_PCH_GBE_TRST_N
J 0
(-2585 4510);
DISPLAY 0.617021 (-2585 4510);
PAINT ORANGE (-2585 4510);
WIRE 16 -1 (-2000 4300)(-2600 4300);
FORCEPROP 2 LAST SIG_NAME JTAG_PCH_GBE_TDI
J 0
(-2585 4310);
DISPLAY 0.617021 (-2585 4310);
PAINT ORANGE (-2585 4310);
WIRE 16 -1 (-2000 4125)(-2600 4125);
FORCEPROP 0 LAST SIG_NAME JTAG_PCH_PLD_TDI
J 0
(-2585 4135);
DISPLAY 0.617021 (-2585 4135);
PAINT ORANGE (-2585 4135);
WIRE 16 -1 (-1475 3575)(-1225 3575);
FORCEPROP 2 LAST SIG_NAME JTAG_TMS
J 1
(-1325 3585);
DISPLAY 0.617021 (-1325 3585);
PAINT ORANGE (-1325 3585);
WIRE 16 -1 (-1475 3575)(-1475 3400);
WIRE 16 -1 (-1800 3575)(-1475 3575);
WIRE 16 -1 (-1475 3400)(-1475 3250);
WIRE 16 -1 (-1800 3400)(-1475 3400);
WIRE 16 -1 (-1475 3075)(-1475 3250);
WIRE 16 -1 (-1800 3250)(-1475 3250);
WIRE 16 -1 (-1800 3075)(-1475 3075);
WIRE 16 -1 (-1475 2875)(-1225 2875);
FORCEPROP 0 LAST SIG_NAME JTAG_TCK
J 1
(-1325 2885);
DISPLAY 0.617021 (-1325 2885);
PAINT ORANGE (-1325 2885);
WIRE 16 -1 (-1475 2875)(-1475 2700);
WIRE 16 -1 (-1800 2875)(-1475 2875);
WIRE 16 -1 (-1475 2700)(-1475 2525);
WIRE 16 -1 (-1800 2700)(-1475 2700);
WIRE 16 -1 (-1475 2350)(-1475 2525);
WIRE 16 -1 (-1800 2525)(-1475 2525);
WIRE 16 -1 (-1800 2350)(-1475 2350);
WIRE 16 -1 (-1800 2150)(-1475 2150);
WIRE 16 -1 (-1475 2150)(-1225 2150);
FORCEPROP 2 LAST SIG_NAME JTAG_TDO
J 1
(-1325 2160);
DISPLAY 0.617021 (-1325 2160);
PAINT ORANGE (-1325 2160);
WIRE 16 -1 (-1475 2150)(-1475 1975);
WIRE 16 -1 (-1475 1975)(-1475 1800);
WIRE 16 -1 (-1800 1975)(-1475 1975);
WIRE 16 -1 (-1475 1625)(-1475 1800);
WIRE 16 -1 (-1800 1800)(-1475 1800);
WIRE 16 -1 (-1800 1625)(-1475 1625);
WIRE 16 -1 (-2000 2875)(-2600 2875);
FORCEPROP 0 LAST SIG_NAME JTAG_PCH_GBE_CLK
J 0
(-2585 2885);
DISPLAY 0.617021 (-2585 2885);
PAINT ORANGE (-2585 2885);
WIRE 16 -1 (-2000 3075)(-2600 3075);
FORCEPROP 2 LAST SIG_NAME JTAG_PLD_TMS
J 0
(-2585 3085);
DISPLAY 0.617021 (-2585 3085);
PAINT ORANGE (-2585 3085);
WIRE 16 -1 (-2000 3775)(-2600 3775);
FORCEPROP 0 LAST SIG_NAME JTAG_PLD_TDI
J 0
(-2585 3785);
DISPLAY 0.617021 (-2585 3785);
PAINT ORANGE (-2585 3785);
WIRE 16 -1 (-2000 3250)(-2600 3250);
FORCEPROP 2 LAST SIG_NAME JTAG_BMC_TMS
J 0
(-2585 3260);
DISPLAY 0.617021 (-2585 3260);
PAINT ORANGE (-2585 3260);
WIRE 16 -1 (-2000 3950)(-2600 3950);
FORCEPROP 2 LAST SIG_NAME JTAG_BMC_TDI
J 0
(-2585 3960);
DISPLAY 0.617021 (-2585 3960);
PAINT ORANGE (-2585 3960);
WIRE 16 -1 (-2000 3575)(-2600 3575);
FORCEPROP 2 LAST SIG_NAME JTAG_PCH_GBE_TMS
J 0
(-2585 3585);
DISPLAY 0.617021 (-2585 3585);
PAINT ORANGE (-2585 3585);
WIRE 16 -1 (-2000 2700)(-2600 2700);
FORCEPROP 0 LAST SIG_NAME JTAG_PCH_PLD_TCK
J 0
(-2585 2710);
DISPLAY 0.617021 (-2585 2710);
PAINT ORANGE (-2585 2710);
WIRE 16 -1 (-2000 2150)(-2600 2150);
FORCEPROP 2 LAST SIG_NAME JTAG_PCH_GBE_TDO
J 0
(-2585 2160);
DISPLAY 0.617021 (-2585 2160);
PAINT ORANGE (-2585 2160);
WIRE 16 -1 (-2000 2525)(-2600 2525);
FORCEPROP 0 LAST SIG_NAME JTAG_BMC_TCK
J 0
(-2585 2535);
DISPLAY 0.617021 (-2585 2535);
PAINT ORANGE (-2585 2535);
WIRE 16 -1 (-2000 2350)(-2600 2350);
FORCEPROP 2 LAST SIG_NAME JTAG_PLD_TCK
J 0
(-2585 2360);
DISPLAY 0.617021 (-2585 2360);
PAINT ORANGE (-2585 2360);
WIRE 16 -1 (-2000 1975)(-2600 1975);
FORCEPROP 0 LAST SIG_NAME JTAG_PCH_PLD_TDO
J 0
(-2585 1985);
DISPLAY 0.617021 (-2585 1985);
PAINT ORANGE (-2585 1985);
WIRE 16 -1 (-2000 3400)(-2600 3400);
FORCEPROP 0 LAST SIG_NAME JTAG_PCH_PLD_TMS
J 0
(-2585 3410);
DISPLAY 0.617021 (-2585 3410);
PAINT ORANGE (-2585 3410);
WIRE 16 -1 (-2000 1625)(-2600 1625);
FORCEPROP 2 LAST SIG_NAME JTAG_PLD_TDO
J 0
(-2585 1635);
DISPLAY 0.617021 (-2585 1635);
PAINT ORANGE (-2585 1635);
WIRE 16 -1 (-2000 1800)(-2600 1800);
FORCEPROP 2 LAST SIG_NAME JTAG_BMC_TDO
J 0
(-2585 1810);
DISPLAY 0.617021 (-2585 1810);
PAINT ORANGE (-2585 1810);
DOT 1 (-1475 1800);
DOT 1 (-1475 1975);
DOT 1 (-175 1725);
DOT 1 (-1475 2150);
DOT 1 (-1475 2525);
DOT 1 (-1475 2700);
DOT 1 (-1475 2875);
DOT 1 (-1475 3250);
DOT 1 (-1475 3400);
DOT 1 (-1475 3575);
DOT 1 (-1475 3950);
DOT 1 (-1475 4300);
DOT 1 (-1475 4125);
DOT 1 (-1475 4675);
DOT 1 (1675 3725);
DOT 1 (2025 3675);
DOT 1 (2325 3425);
DOT 1 (2325 3525);
DOT 1 (1675 4150);
DOT 1 (2025 4150);
FORCENOTE
$CDS_IMAGE|14 Crescent City Management SGPIO Block Diagrams_1.jpg|2737|2125
(2625 1650) 0;
DISPLAY CENTER (2625 1650);
PAINT MONO (2625 1650);
FORCENOTE
ROOM=BMC_DEBUG_HEADER
(-3375 350) 0;
DISPLAY LEFT (-3375 350);
DISPLAY 1.021277 (-3375 350);
PAINT PURPLE (-3375 350);
FORCENOTE
CPLD
(-3325 2725) 0;
DISPLAY LEFT (-3325 2725);
DISPLAY 1.021277 (-3325 2725);
PAINT PURPLE (-3325 2725);
FORCENOTE
BMC
(-3325 2825) 0;
DISPLAY LEFT (-3325 2825);
DISPLAY 1.021277 (-3325 2825);
PAINT PURPLE (-3325 2825);
FORCENOTE
PCH GBE
(-3375 3025) 0;
DISPLAY LEFT (-3375 3025);
DISPLAY 1.021277 (-3375 3025);
PAINT PURPLE (-3375 3025);
FORCENOTE
PCH PLD
(-3375 2925) 0;
DISPLAY LEFT (-3375 2925);
DISPLAY 1.021277 (-3375 2925);
PAINT PURPLE (-3375 2925);
FORCENOTE
DEBUG FOR:
(-3425 3125) 0;
DISPLAY LEFT (-3425 3125);
DISPLAY 1.021277 (-3425 3125);
PAINT PURPLE (-3425 3125);
QUIT
